FILE_TYPE = MACRO_DRAWING;
SET COLOR_WIRE YELLOW;
SET COLOR_PROP ORANGE;
SET COLOR_DOT WHITE;
SET COLOR_ARC YELLOW;
SET COLOR_BODY GREEN;
SET COLOR_NOTE PURPLE;
SET PROP_DISPLAY VALUE;
SET PAGE_NUMBER P302;
FORCEADD Q_RES..1
(-8275 4375);
FORCEPROP 1 LAST LOCATION PR2513
J 0
(-8500 4425);
DISPLAY 0.723404 (-8500 4425);
PAINT AQUA (-8500 4425);
FORCEPROP 0 LAST $SEC 1
J 0
(-8175 4475);
DISPLAY 0.680851 (-8175 4475);
PAINT MONO (-8175 4475);
DISPLAY INVISIBLE (-8175 4475);
FORCEPROP 0 LAST CDS_SEC 1
J 0
(-8175 4475);
DISPLAY 1.021277 (-8175 4475);
DISPLAY INVISIBLE (-8175 4475);
FORCEPROP 1 LASTPIN (-8375 4375) $PN 1
J 0
(-8363 4387);
DISPLAY 0.787234 (-8363 4387);
PAINT MONO (-8363 4387);
FORCEPROP 1 LASTPIN (-8175 4375) $PN 2
J 0
(-8213 4387);
DISPLAY 0.787234 (-8213 4387);
PAINT MONO (-8213 4387);
FORCEPROP 1 LAST MATERIAL CHIP
J 0
(-8175 4425);
DISPLAY 0.723404 (-8175 4425);
PAINT SKYBLUE (-8175 4425);
FORCEPROP 0 LAST ROOM HSC BOM2
J 0
(-8825 4375);
DISPLAY 0.680851 (-8825 4375);
FORCEPROP 1 LAST TOLERANCE 1%
J 0
(-8250 4425);
DISPLAY 0.723404 (-8250 4425);
PAINT SKYBLUE (-8250 4425);
FORCEPROP 1 LAST VALUE 1
J 2
(-8300 4425);
DISPLAY 0.723404 (-8300 4425);
PAINT SKYBLUE (-8300 4425);
FORCEPROP 1 LAST PART_NUMBER CS-1002FB04
J 0
(-8250 4175);
DISPLAY 0.723404 (-8250 4175);
PAINT WHITE (-8250 4175);
DISPLAY INVISIBLE (-8250 4175);
FORCEPROP 1 LAST PATH I15
J 0
(-8325 4525);
DISPLAY 0.978723 (-8325 4525);
PAINT WHITE (-8325 4525);
DISPLAY INVISIBLE (-8325 4525);
FORCEPROP 1 LAST PACK_TYPE 0402LF
J 0
(-8350 4325);
DISPLAY 0.723404 (-8350 4325);
PAINT SKYBLUE (-8350 4325);
DISPLAY INVISIBLE (-8350 4325);
FORCEPROP 1 LAST WATTAGE 1/16W
J 2
(-7950 4325);
DISPLAY 0.723404 (-7950 4325);
PAINT SKYBLUE (-7950 4325);
DISPLAY INVISIBLE (-7950 4325);
FORCEPROP 2 LAST CDS_LIB pure_quanta
J 0
(-8275 4375);
DISPLAY INVISIBLE (-8275 4375);
FORCEADD Q_RES..1
(-8275 4475);
FORCEPROP 1 LAST LOCATION PR2512
J 0
(-8500 4525);
DISPLAY 0.723404 (-8500 4525);
PAINT AQUA (-8500 4525);
FORCEPROP 0 LAST $SEC 1
J 0
(-8175 4575);
DISPLAY 0.680851 (-8175 4575);
PAINT MONO (-8175 4575);
DISPLAY INVISIBLE (-8175 4575);
FORCEPROP 0 LAST CDS_SEC 1
J 0
(-8175 4575);
DISPLAY 1.021277 (-8175 4575);
DISPLAY INVISIBLE (-8175 4575);
FORCEPROP 1 LASTPIN (-8375 4475) $PN 1
J 0
(-8363 4487);
DISPLAY 0.787234 (-8363 4487);
PAINT MONO (-8363 4487);
FORCEPROP 1 LASTPIN (-8175 4475) $PN 2
J 0
(-8213 4487);
DISPLAY 0.787234 (-8213 4487);
PAINT MONO (-8213 4487);
FORCEPROP 1 LAST VALUE 1
J 2
(-8300 4525);
DISPLAY 0.723404 (-8300 4525);
PAINT SKYBLUE (-8300 4525);
FORCEPROP 0 LAST ROOM HSC BOM2
J 0
(-8825 4475);
DISPLAY 0.680851 (-8825 4475);
FORCEPROP 1 LAST MATERIAL CHIP
J 0
(-8175 4525);
DISPLAY 0.723404 (-8175 4525);
PAINT SKYBLUE (-8175 4525);
FORCEPROP 1 LAST TOLERANCE 1%
J 0
(-8250 4525);
DISPLAY 0.723404 (-8250 4525);
PAINT SKYBLUE (-8250 4525);
FORCEPROP 1 LAST PART_NUMBER CS-1002FB04
J 0
(-8250 4275);
DISPLAY 0.723404 (-8250 4275);
PAINT WHITE (-8250 4275);
DISPLAY INVISIBLE (-8250 4275);
FORCEPROP 1 LAST PATH I16
J 0
(-8325 4625);
DISPLAY 0.978723 (-8325 4625);
PAINT WHITE (-8325 4625);
DISPLAY INVISIBLE (-8325 4625);
FORCEPROP 1 LAST WATTAGE 1/16W
J 2
(-7950 4425);
DISPLAY 0.723404 (-7950 4425);
PAINT SKYBLUE (-7950 4425);
DISPLAY INVISIBLE (-7950 4425);
FORCEPROP 1 LAST PACK_TYPE 0402LF
J 0
(-8350 4425);
DISPLAY 0.723404 (-8350 4425);
PAINT SKYBLUE (-8350 4425);
DISPLAY INVISIBLE (-8350 4425);
FORCEPROP 2 LAST CDS_LIB pure_quanta
J 0
(-8275 4475);
DISPLAY INVISIBLE (-8275 4475);
FORCEADD Q_RES..1
(-8275 4575);
FORCEPROP 1 LAST LOCATION PR2511
J 0
(-8500 4625);
DISPLAY 0.723404 (-8500 4625);
PAINT AQUA (-8500 4625);
FORCEPROP 0 LAST $SEC 1
J 0
(-7800 4625);
DISPLAY INVISIBLE (-7800 4625);
FORCEPROP 0 LAST CDS_SEC 1
J 0
(-7800 4625);
DISPLAY INVISIBLE (-7800 4625);
FORCEPROP 1 LASTPIN (-8375 4575) $PN 1
J 0
(-8363 4587);
DISPLAY 0.723404 (-8363 4587);
PAINT MONO (-8363 4587);
FORCEPROP 1 LASTPIN (-8175 4575) $PN 2
J 0
(-8213 4587);
DISPLAY 0.723404 (-8213 4587);
PAINT MONO (-8213 4587);
FORCEPROP 1 LAST TOLERANCE 1%
J 0
(-8250 4625);
DISPLAY 0.723404 (-8250 4625);
PAINT SKYBLUE (-8250 4625);
FORCEPROP 0 LAST ROOM HSC BOM2
J 0
(-8825 4575);
DISPLAY 0.680851 (-8825 4575);
FORCEPROP 1 LAST MATERIAL CHIP
J 0
(-8175 4625);
DISPLAY 0.723404 (-8175 4625);
PAINT SKYBLUE (-8175 4625);
FORCEPROP 1 LAST VALUE 1
J 2
(-8300 4625);
DISPLAY 0.723404 (-8300 4625);
PAINT SKYBLUE (-8300 4625);
FORCEPROP 1 LAST PART_NUMBER CS-1002FB04
J 0
(-8250 4375);
DISPLAY 0.723404 (-8250 4375);
PAINT WHITE (-8250 4375);
DISPLAY INVISIBLE (-8250 4375);
FORCEPROP 1 LAST PATH I17
J 0
(-8325 4725);
DISPLAY 0.978723 (-8325 4725);
PAINT WHITE (-8325 4725);
DISPLAY INVISIBLE (-8325 4725);
FORCEPROP 1 LAST WATTAGE 1/16W
J 2
(-7950 4525);
DISPLAY 0.723404 (-7950 4525);
PAINT SKYBLUE (-7950 4525);
DISPLAY INVISIBLE (-7950 4525);
FORCEPROP 1 LAST PACK_TYPE 0402LF
J 0
(-8350 4525);
DISPLAY 0.723404 (-8350 4525);
PAINT SKYBLUE (-8350 4525);
DISPLAY INVISIBLE (-8350 4525);
FORCEPROP 2 LAST CDS_LIB pure_quanta
J 0
(-8275 4575);
DISPLAY INVISIBLE (-8275 4575);
FORCEADD Q_RES..1
(-8275 4675);
FORCEPROP 1 LAST LOCATION PR2510
J 0
(-8500 4725);
DISPLAY 0.723404 (-8500 4725);
PAINT AQUA (-8500 4725);
FORCEPROP 0 LAST $SEC 1
J 0
(-7800 4725);
DISPLAY INVISIBLE (-7800 4725);
FORCEPROP 0 LAST CDS_SEC 1
J 0
(-7800 4725);
DISPLAY INVISIBLE (-7800 4725);
FORCEPROP 1 LASTPIN (-8375 4675) $PN 1
J 0
(-8363 4687);
DISPLAY 0.723404 (-8363 4687);
PAINT MONO (-8363 4687);
FORCEPROP 1 LASTPIN (-8175 4675) $PN 2
J 0
(-8213 4687);
DISPLAY 0.723404 (-8213 4687);
PAINT MONO (-8213 4687);
FORCEPROP 1 LAST TOLERANCE 1%
J 0
(-8250 4725);
DISPLAY 0.723404 (-8250 4725);
PAINT SKYBLUE (-8250 4725);
FORCEPROP 0 LAST ROOM HSC BOM2
J 0
(-8825 4675);
DISPLAY 0.680851 (-8825 4675);
FORCEPROP 1 LAST MATERIAL CHIP
J 0
(-8175 4725);
DISPLAY 0.723404 (-8175 4725);
PAINT SKYBLUE (-8175 4725);
FORCEPROP 1 LAST VALUE 1
J 2
(-8300 4725);
DISPLAY 0.723404 (-8300 4725);
PAINT SKYBLUE (-8300 4725);
FORCEPROP 1 LAST PART_NUMBER CS-1002FB04
J 0
(-8250 4475);
DISPLAY 0.723404 (-8250 4475);
PAINT WHITE (-8250 4475);
DISPLAY INVISIBLE (-8250 4475);
FORCEPROP 1 LAST PATH I18
J 0
(-8325 4825);
DISPLAY 0.978723 (-8325 4825);
PAINT WHITE (-8325 4825);
DISPLAY INVISIBLE (-8325 4825);
FORCEPROP 1 LAST WATTAGE 1/16W
J 2
(-7950 4625);
DISPLAY 0.723404 (-7950 4625);
PAINT SKYBLUE (-7950 4625);
DISPLAY INVISIBLE (-7950 4625);
FORCEPROP 1 LAST PACK_TYPE 0402LF
J 0
(-8350 4625);
DISPLAY 0.723404 (-8350 4625);
PAINT SKYBLUE (-8350 4625);
DISPLAY INVISIBLE (-8350 4625);
FORCEPROP 2 LAST CDS_LIB pure_quanta
J 0
(-8275 4675);
DISPLAY INVISIBLE (-8275 4675);
FORCEADD OFFPAGE..4
R 2
(-7000 1175);
FORCEPROP 2 LAST $XR0 268 
J 0
(-7252 1175);
DISPLAY 0.638298 (-7252 1175);
PAINT MONO (-7252 1175);
FORCEPROP 2 LAST PATH I19
J 0
(-6950 1250);
DISPLAY 0.680851 (-6950 1250);
DISPLAY INVISIBLE (-6950 1250);
FORCEPROP 1 LAST COMMENT_BODY TRUE
J 2
(-6975 1075);
DISPLAY 0.872340 (-6975 1075);
PAINT GREEN (-6975 1075);
DISPLAY INVISIBLE (-6975 1075);
FORCEPROP 1 LAST OFFPAGE TRUE
J 2
(-7325 1050);
DISPLAY 0.872340 (-7325 1050);
PAINT GREEN (-7325 1050);
DISPLAY INVISIBLE (-7325 1050);
FORCEPROP 2 LAST CDS_LIB standard
J 0
(-7000 1175);
DISPLAY INVISIBLE (-7000 1175);
FORCEADD OFFPAGE..4
(-7250 2100);
FORCEPROP 2 LAST $XR0 267 
J 0
(-7064 2100);
DISPLAY 0.638298 (-7064 2100);
PAINT MONO (-7064 2100);
FORCEPROP 2 LAST PATH I20
J 0
(-7075 2175);
DISPLAY 0.680851 (-7075 2175);
DISPLAY INVISIBLE (-7075 2175);
FORCEPROP 1 LAST COMMENT_BODY TRUE
J 0
(-7275 2000);
DISPLAY 0.872340 (-7275 2000);
PAINT GREEN (-7275 2000);
DISPLAY INVISIBLE (-7275 2000);
FORCEPROP 1 LAST OFFPAGE TRUE
J 0
(-6925 1975);
DISPLAY 0.872340 (-6925 1975);
PAINT GREEN (-6925 1975);
DISPLAY INVISIBLE (-6925 1975);
FORCEPROP 2 LAST CDS_LIB standard
J 0
(-7250 2100);
DISPLAY INVISIBLE (-7250 2100);
FORCEADD OFFPAGE..4
(-7250 2300);
FORCEPROP 2 LAST $XR0 267 
J 0
(-7064 2300);
DISPLAY 0.638298 (-7064 2300);
PAINT MONO (-7064 2300);
FORCEPROP 2 LAST PATH I21
J 0
(-7075 2375);
DISPLAY 0.680851 (-7075 2375);
DISPLAY INVISIBLE (-7075 2375);
FORCEPROP 1 LAST COMMENT_BODY TRUE
J 0
(-7275 2200);
DISPLAY 0.872340 (-7275 2200);
PAINT GREEN (-7275 2200);
DISPLAY INVISIBLE (-7275 2200);
FORCEPROP 1 LAST OFFPAGE TRUE
J 0
(-6925 2175);
DISPLAY 0.872340 (-6925 2175);
PAINT GREEN (-6925 2175);
DISPLAY INVISIBLE (-6925 2175);
FORCEPROP 2 LAST CDS_LIB standard
J 0
(-7250 2300);
DISPLAY INVISIBLE (-7250 2300);
FORCEADD OFFPAGE..4
(-7250 2200);
FORCEPROP 2 LAST $XR0 267 
J 0
(-7064 2200);
DISPLAY 0.638298 (-7064 2200);
PAINT MONO (-7064 2200);
FORCEPROP 2 LAST PATH I22
J 0
(-7075 2275);
DISPLAY 0.680851 (-7075 2275);
DISPLAY INVISIBLE (-7075 2275);
FORCEPROP 1 LAST COMMENT_BODY TRUE
J 0
(-7275 2100);
DISPLAY 0.872340 (-7275 2100);
PAINT GREEN (-7275 2100);
DISPLAY INVISIBLE (-7275 2100);
FORCEPROP 1 LAST OFFPAGE TRUE
J 0
(-6925 2075);
DISPLAY 0.872340 (-6925 2075);
PAINT GREEN (-6925 2075);
DISPLAY INVISIBLE (-6925 2075);
FORCEPROP 2 LAST CDS_LIB standard
J 0
(-7250 2200);
DISPLAY INVISIBLE (-7250 2200);
FORCEADD OFFPAGE..4
(-7250 2400);
FORCEPROP 2 LAST $XR0 267 
J 0
(-7064 2400);
DISPLAY 0.638298 (-7064 2400);
PAINT MONO (-7064 2400);
FORCEPROP 2 LAST PATH I23
J 0
(-7075 2475);
DISPLAY 0.680851 (-7075 2475);
DISPLAY INVISIBLE (-7075 2475);
FORCEPROP 1 LAST COMMENT_BODY TRUE
J 0
(-7275 2300);
DISPLAY 0.872340 (-7275 2300);
PAINT GREEN (-7275 2300);
DISPLAY INVISIBLE (-7275 2300);
FORCEPROP 1 LAST OFFPAGE TRUE
J 0
(-6925 2275);
DISPLAY 0.872340 (-6925 2275);
PAINT GREEN (-6925 2275);
DISPLAY INVISIBLE (-6925 2275);
FORCEPROP 2 LAST CDS_LIB standard
J 0
(-7250 2400);
DISPLAY INVISIBLE (-7250 2400);
FORCEADD OFFPAGE..2
(-7250 2500);
FORCEPROP 2 LAST $XR0 268 
J 0
(-7061 2500);
DISPLAY 0.638298 (-7061 2500);
PAINT MONO (-7061 2500);
FORCEPROP 2 LAST PATH I24
J 0
(-7075 2575);
DISPLAY 0.680851 (-7075 2575);
DISPLAY INVISIBLE (-7075 2575);
FORCEPROP 1 LAST COMMENT_BODY TRUE
J 0
(-7295 2405);
DISPLAY 0.872340 (-7295 2405);
PAINT GREEN (-7295 2405);
DISPLAY INVISIBLE (-7295 2405);
FORCEPROP 1 LAST OFFPAGE TRUE
J 0
(-6925 2375);
DISPLAY 0.872340 (-6925 2375);
PAINT AQUA (-6925 2375);
DISPLAY INVISIBLE (-6925 2375);
FORCEPROP 2 LAST CDS_LIB standard
J 0
(-7250 2500);
DISPLAY INVISIBLE (-7250 2500);
FORCEADD OFFPAGE..4
(-7250 2850);
FORCEPROP 2 LAST $XR0 267 
J 0
(-7064 2850);
DISPLAY 0.638298 (-7064 2850);
PAINT MONO (-7064 2850);
FORCEPROP 2 LAST PATH I25
J 0
(-7075 2925);
DISPLAY 0.680851 (-7075 2925);
DISPLAY INVISIBLE (-7075 2925);
FORCEPROP 1 LAST COMMENT_BODY TRUE
J 0
(-7275 2750);
DISPLAY 0.872340 (-7275 2750);
PAINT GREEN (-7275 2750);
DISPLAY INVISIBLE (-7275 2750);
FORCEPROP 1 LAST OFFPAGE TRUE
J 0
(-6925 2725);
DISPLAY 0.872340 (-6925 2725);
PAINT GREEN (-6925 2725);
DISPLAY INVISIBLE (-6925 2725);
FORCEPROP 2 LAST CDS_LIB standard
J 0
(-7250 2850);
DISPLAY INVISIBLE (-7250 2850);
FORCEADD OFFPAGE..4
(-7250 2950);
FORCEPROP 2 LAST $XR0 267 
J 0
(-7064 2950);
DISPLAY 0.638298 (-7064 2950);
PAINT MONO (-7064 2950);
FORCEPROP 2 LAST PATH I26
J 0
(-7075 3025);
DISPLAY 0.680851 (-7075 3025);
DISPLAY INVISIBLE (-7075 3025);
FORCEPROP 1 LAST COMMENT_BODY TRUE
J 0
(-7275 2850);
DISPLAY 0.872340 (-7275 2850);
PAINT GREEN (-7275 2850);
DISPLAY INVISIBLE (-7275 2850);
FORCEPROP 1 LAST OFFPAGE TRUE
J 0
(-6925 2825);
DISPLAY 0.872340 (-6925 2825);
PAINT GREEN (-6925 2825);
DISPLAY INVISIBLE (-6925 2825);
FORCEPROP 2 LAST CDS_LIB standard
J 0
(-7250 2950);
DISPLAY INVISIBLE (-7250 2950);
FORCEADD Q_RES..2
(-6550 1575);
FORCEPROP 1 LAST LOCATION PR2528
J 0
(-6505 1700);
DISPLAY 0.723404 (-6505 1700);
PAINT AQUA (-6505 1700);
FORCEPROP 0 LAST $SEC 1
J 0
(-6500 1750);
DISPLAY INVISIBLE (-6500 1750);
FORCEPROP 0 LAST CDS_SEC 1
J 0
(-6500 1750);
DISPLAY INVISIBLE (-6500 1750);
FORCEPROP 1 LASTPIN (-6550 1675) $PN 1
J 0
(-6545 1637);
DISPLAY 0.787234 (-6545 1637);
DISPLAY INVISIBLE (-6545 1637);
FORCEPROP 1 LASTPIN (-6550 1475) $PN 2
J 0
(-6545 1485);
DISPLAY 0.787234 (-6545 1485);
DISPLAY INVISIBLE (-6545 1485);
FORCEPROP 0 LAST ROOM HSC BOM2
J 0
(-6500 1750);
DISPLAY 0.680851 (-6500 1750);
FORCEPROP 1 LAST VALUE 10
J 0
(-6505 1650);
DISPLAY 0.723404 (-6505 1650);
PAINT SKYBLUE (-6505 1650);
FORCEPROP 1 LAST WATTAGE 1/16W
J 0
(-6510 1550);
DISPLAY 0.723404 (-6510 1550);
PAINT SKYBLUE (-6510 1550);
FORCEPROP 1 LAST MATERIAL CHIP
J 0
(-6510 1500);
DISPLAY 0.723404 (-6510 1500);
PAINT SKYBLUE (-6510 1500);
FORCEPROP 1 LAST TOLERANCE 1%
J 0
(-6505 1600);
DISPLAY 0.723404 (-6505 1600);
PAINT SKYBLUE (-6505 1600);
FORCEPROP 1 LAST PACK_TYPE 0402LF
J 0
(-6510 1400);
DISPLAY 0.723404 (-6510 1400);
PAINT SKYBLUE (-6510 1400);
FORCEPROP 1 LAST PART_NUMBER CS01002FB07
J 0
(-6510 1450);
DISPLAY 0.723404 (-6510 1450);
PAINT WHITE (-6510 1450);
DISPLAY INVISIBLE (-6510 1450);
FORCEPROP 1 LAST PATH I27
J 0
(-6500 1750);
DISPLAY 0.978723 (-6500 1750);
PAINT WHITE (-6500 1750);
DISPLAY INVISIBLE (-6500 1750);
FORCEPROP 2 LAST CDS_LIB pure_quanta
J 0
(-6550 1575);
PAINT MONO (-6550 1575);
DISPLAY INVISIBLE (-6550 1575);
FORCEADD Q_RES..2
(-5675 1575);
FORCEPROP 1 LAST LOCATION PR2529
J 0
(-5630 1700);
DISPLAY 0.723404 (-5630 1700);
PAINT AQUA (-5630 1700);
FORCEPROP 0 LAST $SEC 1
J 0
(-5625 1750);
DISPLAY INVISIBLE (-5625 1750);
FORCEPROP 0 LAST CDS_SEC 1
J 0
(-5625 1750);
DISPLAY INVISIBLE (-5625 1750);
FORCEPROP 1 LASTPIN (-5675 1675) $PN 1
J 0
(-5670 1637);
DISPLAY 0.787234 (-5670 1637);
DISPLAY INVISIBLE (-5670 1637);
FORCEPROP 1 LASTPIN (-5675 1475) $PN 2
J 0
(-5670 1485);
DISPLAY 0.787234 (-5670 1485);
DISPLAY INVISIBLE (-5670 1485);
FORCEPROP 0 LAST ROOM HSC BOM2
J 0
(-5625 1750);
DISPLAY 0.680851 (-5625 1750);
FORCEPROP 1 LAST TOLERANCE 1%
J 0
(-5630 1600);
DISPLAY 0.723404 (-5630 1600);
PAINT SKYBLUE (-5630 1600);
FORCEPROP 1 LAST MATERIAL CHIP
J 0
(-5635 1500);
DISPLAY 0.723404 (-5635 1500);
PAINT SKYBLUE (-5635 1500);
FORCEPROP 1 LAST VALUE 10
J 0
(-5630 1650);
DISPLAY 0.723404 (-5630 1650);
PAINT SKYBLUE (-5630 1650);
FORCEPROP 1 LAST WATTAGE 1/16W
J 0
(-5635 1550);
DISPLAY 0.723404 (-5635 1550);
PAINT SKYBLUE (-5635 1550);
FORCEPROP 1 LAST PACK_TYPE 0402LF
J 0
(-5635 1400);
DISPLAY 0.723404 (-5635 1400);
PAINT SKYBLUE (-5635 1400);
FORCEPROP 1 LAST PART_NUMBER CS01002FB07
J 0
(-5635 1450);
DISPLAY 0.723404 (-5635 1450);
PAINT WHITE (-5635 1450);
DISPLAY INVISIBLE (-5635 1450);
FORCEPROP 1 LAST PATH I28
J 0
(-5625 1750);
DISPLAY 0.978723 (-5625 1750);
PAINT WHITE (-5625 1750);
DISPLAY INVISIBLE (-5625 1750);
FORCEPROP 2 LAST CDS_LIB pure_quanta
J 0
(-5675 1575);
PAINT MONO (-5675 1575);
DISPLAY INVISIBLE (-5675 1575);
FORCEADD MOSFET_NCH_1D3S..1
R 6
(-6200 2275);
FORCEPROP 1 LAST LOCATION PPQ5
J 0
(-6048 2309);
DISPLAY 0.723404 (-6048 2309);
PAINT AQUA (-6048 2309);
FORCEPROP 0 LAST $SEC 1
J 0
(-6025 2475);
DISPLAY INVISIBLE (-6025 2475);
FORCEPROP 0 LAST CDS_SEC 1
J 0
(-6025 2475);
DISPLAY INVISIBLE (-6025 2475);
FORCEPROP 0 LASTPIN (-6100 2025) $PN 1
R 1
J 2
(-6110 2015);
DISPLAY 0.808511 (-6110 2015);
FORCEPROP 0 LASTPIN (-6200 2025) $PN 2
R 1
J 2
(-6210 2015);
DISPLAY 0.808511 (-6210 2015);
FORCEPROP 0 LASTPIN (-6300 2025) $PN 3
R 1
J 2
(-6310 2015);
DISPLAY 0.808511 (-6310 2015);
FORCEPROP 0 LASTPIN (-6400 2225) $PN 4
J 2
(-6410 2235);
DISPLAY 0.808511 (-6410 2235);
FORCEPROP 0 LASTPIN (-6200 2525) $PN 5
R 1
J 0
(-6210 2535);
DISPLAY 0.808511 (-6210 2535);
FORCEPROP 0 LAST ROOM HSC BOM2
J 0
(-6025 2475);
DISPLAY 0.680851 (-6025 2475);
FORCEPROP 2 LAST VALUE PSMNR58-30YLH
J 0
(-6025 2252);
DISPLAY 0.723404 (-6025 2252);
PAINT SKYBLUE (-6025 2252);
FORCEPROP 2 LAST PART_TYPE SMLF
J 0
(-6025 2202);
DISPLAY 1.021277 (-6025 2202);
FORCEPROP 1 LAST MATERIAL IC
J 0
(-6048 2425);
DISPLAY 0.723404 (-6048 2425);
PAINT SKYBLUE (-6048 2425);
FORCEPROP 1 LAST PART_NUMBER BAMNR580000
J 0
(-6048 2366);
DISPLAY 0.723404 (-6048 2366);
PAINT WHITE (-6048 2366);
DISPLAY INVISIBLE (-6048 2366);
FORCEPROP 1 LAST PATH I29
J 0
(-6200 2275);
DISPLAY 0.723404 (-6200 2275);
PAINT GREEN (-6200 2275);
DISPLAY INVISIBLE (-6200 2275);
FORCEPROP 1 LAST CDS_LMAN_SYM_OUTLINE -150,200,150,-200
J 0
(-6200 2253);
DISPLAY 0.468085 (-6200 2253);
PAINT GREEN (-6200 2253);
DISPLAY INVISIBLE (-6200 2253);
FORCEPROP 1 LAST NEEDS_NO_SIZE TRUE
J 0
(-6200 2254);
DISPLAY 0.468085 (-6200 2254);
PAINT GREEN (-6200 2254);
DISPLAY INVISIBLE (-6200 2254);
FORCEPROP 2 LAST CDS_LIB pure_quanta
J 0
(-6200 2228);
DISPLAY INVISIBLE (-6200 2228);
FORCEADD OFFPAGE..4
(-7250 3050);
FORCEPROP 2 LAST $XR0 267 
J 0
(-7064 3050);
DISPLAY 0.638298 (-7064 3050);
PAINT MONO (-7064 3050);
FORCEPROP 2 LAST PATH I30
J 0
(-7075 3125);
DISPLAY 0.680851 (-7075 3125);
DISPLAY INVISIBLE (-7075 3125);
FORCEPROP 1 LAST COMMENT_BODY TRUE
J 0
(-7275 2950);
DISPLAY 0.872340 (-7275 2950);
PAINT GREEN (-7275 2950);
DISPLAY INVISIBLE (-7275 2950);
FORCEPROP 1 LAST OFFPAGE TRUE
J 0
(-6925 2925);
DISPLAY 0.872340 (-6925 2925);
PAINT GREEN (-6925 2925);
DISPLAY INVISIBLE (-6925 2925);
FORCEPROP 2 LAST CDS_LIB standard
J 0
(-7250 3050);
DISPLAY INVISIBLE (-7250 3050);
FORCEADD OFFPAGE..4
(-7250 3150);
FORCEPROP 2 LAST $XR0 267 
J 0
(-7064 3150);
DISPLAY 0.638298 (-7064 3150);
PAINT MONO (-7064 3150);
FORCEPROP 2 LAST PATH I31
J 0
(-7075 3225);
DISPLAY 0.680851 (-7075 3225);
DISPLAY INVISIBLE (-7075 3225);
FORCEPROP 1 LAST COMMENT_BODY TRUE
J 0
(-7275 3050);
DISPLAY 0.872340 (-7275 3050);
PAINT GREEN (-7275 3050);
DISPLAY INVISIBLE (-7275 3050);
FORCEPROP 1 LAST OFFPAGE TRUE
J 0
(-6925 3025);
DISPLAY 0.872340 (-6925 3025);
PAINT GREEN (-6925 3025);
DISPLAY INVISIBLE (-6925 3025);
FORCEPROP 2 LAST CDS_LIB standard
J 0
(-7250 3150);
DISPLAY INVISIBLE (-7250 3150);
FORCEADD OFFPAGE..2
(-7250 3250);
FORCEPROP 2 LAST $XR0 268 
J 0
(-7061 3250);
DISPLAY 0.638298 (-7061 3250);
PAINT MONO (-7061 3250);
FORCEPROP 2 LAST PATH I32
J 0
(-7075 3325);
DISPLAY 0.680851 (-7075 3325);
DISPLAY INVISIBLE (-7075 3325);
FORCEPROP 1 LAST COMMENT_BODY TRUE
J 0
(-7295 3155);
DISPLAY 0.872340 (-7295 3155);
PAINT GREEN (-7295 3155);
DISPLAY INVISIBLE (-7295 3155);
FORCEPROP 1 LAST OFFPAGE TRUE
J 0
(-6925 3125);
DISPLAY 0.872340 (-6925 3125);
PAINT AQUA (-6925 3125);
DISPLAY INVISIBLE (-6925 3125);
FORCEPROP 2 LAST CDS_LIB standard
J 0
(-7250 3250);
DISPLAY INVISIBLE (-7250 3250);
FORCEADD OFFPAGE..4
(-7275 3525);
FORCEPROP 2 LAST $XR0 267 
J 0
(-7089 3525);
DISPLAY 0.638298 (-7089 3525);
PAINT MONO (-7089 3525);
FORCEPROP 2 LAST $XR1 268 
J 0
(-6969 3525);
DISPLAY 0.638298 (-6969 3525);
PAINT MONO (-6969 3525);
FORCEPROP 2 LAST PATH I33
J 0
(-7100 3600);
DISPLAY 0.680851 (-7100 3600);
DISPLAY INVISIBLE (-7100 3600);
FORCEPROP 1 LAST COMMENT_BODY TRUE
J 0
(-7300 3425);
DISPLAY 0.872340 (-7300 3425);
PAINT GREEN (-7300 3425);
DISPLAY INVISIBLE (-7300 3425);
FORCEPROP 1 LAST OFFPAGE TRUE
J 0
(-6950 3400);
DISPLAY 0.872340 (-6950 3400);
PAINT GREEN (-6950 3400);
DISPLAY INVISIBLE (-6950 3400);
FORCEPROP 2 LAST CDS_LIB standard
J 0
(-7275 3525);
DISPLAY INVISIBLE (-7275 3525);
FORCEADD OFFPAGE..4
(-7275 3625);
FORCEPROP 2 LAST $XR0 267 
J 0
(-7089 3625);
DISPLAY 0.638298 (-7089 3625);
PAINT MONO (-7089 3625);
FORCEPROP 2 LAST PATH I34
J 0
(-7100 3700);
DISPLAY 0.680851 (-7100 3700);
DISPLAY INVISIBLE (-7100 3700);
FORCEPROP 1 LAST COMMENT_BODY TRUE
J 0
(-7300 3525);
DISPLAY 0.872340 (-7300 3525);
PAINT GREEN (-7300 3525);
DISPLAY INVISIBLE (-7300 3525);
FORCEPROP 1 LAST OFFPAGE TRUE
J 0
(-6950 3500);
DISPLAY 0.872340 (-6950 3500);
PAINT GREEN (-6950 3500);
DISPLAY INVISIBLE (-6950 3500);
FORCEPROP 2 LAST CDS_LIB standard
J 0
(-7275 3625);
DISPLAY INVISIBLE (-7275 3625);
FORCEADD OFFPAGE..4
(-7275 3725);
FORCEPROP 2 LAST $XR0 267 
J 0
(-7089 3725);
DISPLAY 0.638298 (-7089 3725);
PAINT MONO (-7089 3725);
FORCEPROP 2 LAST PATH I35
J 0
(-7100 3800);
DISPLAY 0.680851 (-7100 3800);
DISPLAY INVISIBLE (-7100 3800);
FORCEPROP 1 LAST COMMENT_BODY TRUE
J 0
(-7300 3625);
DISPLAY 0.872340 (-7300 3625);
PAINT GREEN (-7300 3625);
DISPLAY INVISIBLE (-7300 3625);
FORCEPROP 1 LAST OFFPAGE TRUE
J 0
(-6950 3600);
DISPLAY 0.872340 (-6950 3600);
PAINT GREEN (-6950 3600);
DISPLAY INVISIBLE (-6950 3600);
FORCEPROP 2 LAST CDS_LIB standard
J 0
(-7275 3725);
DISPLAY INVISIBLE (-7275 3725);
FORCEADD OFFPAGE..4
(-7275 3825);
FORCEPROP 2 LAST $XR0 267 
J 0
(-7089 3825);
DISPLAY 0.638298 (-7089 3825);
PAINT MONO (-7089 3825);
FORCEPROP 2 LAST PATH I36
J 0
(-7100 3900);
DISPLAY 0.680851 (-7100 3900);
DISPLAY INVISIBLE (-7100 3900);
FORCEPROP 1 LAST COMMENT_BODY TRUE
J 0
(-7300 3725);
DISPLAY 0.872340 (-7300 3725);
PAINT GREEN (-7300 3725);
DISPLAY INVISIBLE (-7300 3725);
FORCEPROP 1 LAST OFFPAGE TRUE
J 0
(-6950 3700);
DISPLAY 0.872340 (-6950 3700);
PAINT GREEN (-6950 3700);
DISPLAY INVISIBLE (-6950 3700);
FORCEPROP 2 LAST CDS_LIB standard
J 0
(-7275 3825);
DISPLAY INVISIBLE (-7275 3825);
FORCEADD OFFPAGE..4
(-7275 3925);
FORCEPROP 2 LAST $XR0 267 
J 0
(-7089 3925);
DISPLAY 0.638298 (-7089 3925);
PAINT MONO (-7089 3925);
FORCEPROP 2 LAST PATH I37
J 0
(-7100 4000);
DISPLAY 0.680851 (-7100 4000);
DISPLAY INVISIBLE (-7100 4000);
FORCEPROP 1 LAST COMMENT_BODY TRUE
J 0
(-7300 3825);
DISPLAY 0.872340 (-7300 3825);
PAINT GREEN (-7300 3825);
DISPLAY INVISIBLE (-7300 3825);
FORCEPROP 1 LAST OFFPAGE TRUE
J 0
(-6950 3800);
DISPLAY 0.872340 (-6950 3800);
PAINT GREEN (-6950 3800);
DISPLAY INVISIBLE (-6950 3800);
FORCEPROP 2 LAST CDS_LIB standard
J 0
(-7275 3925);
DISPLAY INVISIBLE (-7275 3925);
FORCEADD OFFPAGE..2
(-7275 4025);
FORCEPROP 2 LAST $XR0 268 
J 0
(-7086 4025);
DISPLAY 0.638298 (-7086 4025);
PAINT MONO (-7086 4025);
FORCEPROP 2 LAST PATH I38
J 0
(-7100 4100);
DISPLAY 0.680851 (-7100 4100);
DISPLAY INVISIBLE (-7100 4100);
FORCEPROP 1 LAST COMMENT_BODY TRUE
J 0
(-7320 3930);
DISPLAY 0.872340 (-7320 3930);
PAINT GREEN (-7320 3930);
DISPLAY INVISIBLE (-7320 3930);
FORCEPROP 1 LAST OFFPAGE TRUE
J 0
(-6950 3900);
DISPLAY 0.872340 (-6950 3900);
PAINT AQUA (-6950 3900);
DISPLAY INVISIBLE (-6950 3900);
FORCEPROP 2 LAST CDS_LIB standard
J 0
(-7275 4025);
DISPLAY INVISIBLE (-7275 4025);
FORCEADD OFFPAGE..4
(-7275 4275);
FORCEPROP 2 LAST $XR0 267 
J 0
(-7089 4275);
DISPLAY 0.638298 (-7089 4275);
PAINT MONO (-7089 4275);
FORCEPROP 2 LAST $XR1 268 
J 0
(-6969 4275);
DISPLAY 0.638298 (-6969 4275);
PAINT MONO (-6969 4275);
FORCEPROP 2 LAST PATH I39
J 0
(-7100 4350);
DISPLAY 0.680851 (-7100 4350);
DISPLAY INVISIBLE (-7100 4350);
FORCEPROP 1 LAST COMMENT_BODY TRUE
J 0
(-7300 4175);
DISPLAY 0.872340 (-7300 4175);
PAINT GREEN (-7300 4175);
DISPLAY INVISIBLE (-7300 4175);
FORCEPROP 1 LAST OFFPAGE TRUE
J 0
(-6950 4150);
DISPLAY 0.872340 (-6950 4150);
PAINT GREEN (-6950 4150);
DISPLAY INVISIBLE (-6950 4150);
FORCEPROP 2 LAST CDS_LIB standard
J 0
(-7275 4275);
DISPLAY INVISIBLE (-7275 4275);
FORCEADD OFFPAGE..4
(-7275 4375);
FORCEPROP 2 LAST $XR0 267 
J 0
(-7089 4375);
DISPLAY 0.638298 (-7089 4375);
PAINT MONO (-7089 4375);
FORCEPROP 2 LAST PATH I40
J 0
(-7100 4450);
DISPLAY 0.680851 (-7100 4450);
DISPLAY INVISIBLE (-7100 4450);
FORCEPROP 1 LAST COMMENT_BODY TRUE
J 0
(-7300 4275);
DISPLAY 0.872340 (-7300 4275);
PAINT GREEN (-7300 4275);
DISPLAY INVISIBLE (-7300 4275);
FORCEPROP 1 LAST OFFPAGE TRUE
J 0
(-6950 4250);
DISPLAY 0.872340 (-6950 4250);
PAINT GREEN (-6950 4250);
DISPLAY INVISIBLE (-6950 4250);
FORCEPROP 2 LAST CDS_LIB standard
J 0
(-7275 4375);
DISPLAY INVISIBLE (-7275 4375);
FORCEADD OFFPAGE..4
(-7275 4475);
FORCEPROP 2 LAST $XR0 267 
J 0
(-7089 4475);
DISPLAY 0.638298 (-7089 4475);
PAINT MONO (-7089 4475);
FORCEPROP 2 LAST PATH I41
J 0
(-7100 4550);
DISPLAY 0.680851 (-7100 4550);
DISPLAY INVISIBLE (-7100 4550);
FORCEPROP 1 LAST COMMENT_BODY TRUE
J 0
(-7300 4375);
DISPLAY 0.872340 (-7300 4375);
PAINT GREEN (-7300 4375);
DISPLAY INVISIBLE (-7300 4375);
FORCEPROP 1 LAST OFFPAGE TRUE
J 0
(-6950 4350);
DISPLAY 0.872340 (-6950 4350);
PAINT GREEN (-6950 4350);
DISPLAY INVISIBLE (-6950 4350);
FORCEPROP 2 LAST CDS_LIB standard
J 0
(-7275 4475);
DISPLAY INVISIBLE (-7275 4475);
FORCEADD OFFPAGE..4
(-7275 4575);
FORCEPROP 2 LAST $XR0 267 
J 0
(-7089 4575);
DISPLAY 0.638298 (-7089 4575);
PAINT MONO (-7089 4575);
FORCEPROP 2 LAST PATH I42
J 0
(-7100 4650);
DISPLAY 0.680851 (-7100 4650);
DISPLAY INVISIBLE (-7100 4650);
FORCEPROP 1 LAST COMMENT_BODY TRUE
J 0
(-7300 4475);
DISPLAY 0.872340 (-7300 4475);
PAINT GREEN (-7300 4475);
DISPLAY INVISIBLE (-7300 4475);
FORCEPROP 1 LAST OFFPAGE TRUE
J 0
(-6950 4450);
DISPLAY 0.872340 (-6950 4450);
PAINT GREEN (-6950 4450);
DISPLAY INVISIBLE (-6950 4450);
FORCEPROP 2 LAST CDS_LIB standard
J 0
(-7275 4575);
DISPLAY INVISIBLE (-7275 4575);
FORCEADD OFFPAGE..4
(-7275 4675);
FORCEPROP 2 LAST $XR0 267 
J 0
(-7089 4675);
DISPLAY 0.638298 (-7089 4675);
PAINT MONO (-7089 4675);
FORCEPROP 2 LAST PATH I43
J 0
(-7100 4750);
DISPLAY 0.680851 (-7100 4750);
DISPLAY INVISIBLE (-7100 4750);
FORCEPROP 1 LAST COMMENT_BODY TRUE
J 0
(-7300 4575);
DISPLAY 0.872340 (-7300 4575);
PAINT GREEN (-7300 4575);
DISPLAY INVISIBLE (-7300 4575);
FORCEPROP 1 LAST OFFPAGE TRUE
J 0
(-6950 4550);
DISPLAY 0.872340 (-6950 4550);
PAINT GREEN (-6950 4550);
DISPLAY INVISIBLE (-6950 4550);
FORCEPROP 2 LAST CDS_LIB standard
J 0
(-7275 4675);
DISPLAY INVISIBLE (-7275 4675);
FORCEADD OFFPAGE..2
(-7275 4775);
FORCEPROP 2 LAST $XR0 268 
J 0
(-7086 4775);
DISPLAY 0.638298 (-7086 4775);
PAINT MONO (-7086 4775);
FORCEPROP 2 LAST PATH I44
J 0
(-7100 4850);
DISPLAY 0.680851 (-7100 4850);
DISPLAY INVISIBLE (-7100 4850);
FORCEPROP 1 LAST COMMENT_BODY TRUE
J 0
(-7320 4680);
DISPLAY 0.872340 (-7320 4680);
PAINT GREEN (-7320 4680);
DISPLAY INVISIBLE (-7320 4680);
FORCEPROP 1 LAST OFFPAGE TRUE
J 0
(-6950 4650);
DISPLAY 0.872340 (-6950 4650);
PAINT AQUA (-6950 4650);
DISPLAY INVISIBLE (-6950 4650);
FORCEPROP 2 LAST CDS_LIB standard
J 0
(-7275 4775);
DISPLAY INVISIBLE (-7275 4775);
FORCEADD Q_RES..2
(-4825 1575);
FORCEPROP 1 LAST LOCATION PR2530
J 0
(-4780 1700);
DISPLAY 0.723404 (-4780 1700);
PAINT AQUA (-4780 1700);
FORCEPROP 0 LAST $SEC 1
J 0
(-4775 1750);
DISPLAY INVISIBLE (-4775 1750);
FORCEPROP 0 LAST CDS_SEC 1
J 0
(-4775 1750);
DISPLAY INVISIBLE (-4775 1750);
FORCEPROP 1 LASTPIN (-4825 1675) $PN 1
J 0
(-4820 1637);
DISPLAY 0.787234 (-4820 1637);
DISPLAY INVISIBLE (-4820 1637);
FORCEPROP 1 LASTPIN (-4825 1475) $PN 2
J 0
(-4820 1485);
DISPLAY 0.787234 (-4820 1485);
DISPLAY INVISIBLE (-4820 1485);
FORCEPROP 0 LAST ROOM HSC BOM2
J 0
(-4775 1750);
DISPLAY 0.680851 (-4775 1750);
FORCEPROP 1 LAST MATERIAL CHIP
J 0
(-4785 1500);
DISPLAY 0.723404 (-4785 1500);
PAINT SKYBLUE (-4785 1500);
FORCEPROP 1 LAST WATTAGE 1/16W
J 0
(-4785 1550);
DISPLAY 0.723404 (-4785 1550);
PAINT SKYBLUE (-4785 1550);
FORCEPROP 1 LAST TOLERANCE 1%
J 0
(-4780 1600);
DISPLAY 0.723404 (-4780 1600);
PAINT SKYBLUE (-4780 1600);
FORCEPROP 1 LAST VALUE 10
J 0
(-4780 1650);
DISPLAY 0.723404 (-4780 1650);
PAINT SKYBLUE (-4780 1650);
FORCEPROP 1 LAST PACK_TYPE 0402LF
J 0
(-4785 1400);
DISPLAY 0.723404 (-4785 1400);
PAINT SKYBLUE (-4785 1400);
FORCEPROP 1 LAST PART_NUMBER CS01002FB07
J 0
(-4785 1450);
DISPLAY 0.723404 (-4785 1450);
PAINT WHITE (-4785 1450);
DISPLAY INVISIBLE (-4785 1450);
FORCEPROP 1 LAST PATH I45
J 0
(-4775 1750);
DISPLAY 0.978723 (-4775 1750);
PAINT WHITE (-4775 1750);
DISPLAY INVISIBLE (-4775 1750);
FORCEPROP 2 LAST CDS_LIB pure_quanta
J 0
(-4825 1575);
PAINT MONO (-4825 1575);
DISPLAY INVISIBLE (-4825 1575);
FORCEADD MOSFET_NCH_1D3S..1
R 6
(-5325 2300);
FORCEPROP 1 LAST LOCATION PPQ6
J 0
(-5173 2334);
DISPLAY 0.723404 (-5173 2334);
PAINT AQUA (-5173 2334);
FORCEPROP 0 LAST $SEC 1
J 0
(-5150 2500);
DISPLAY INVISIBLE (-5150 2500);
FORCEPROP 0 LAST CDS_SEC 1
J 0
(-5150 2500);
DISPLAY INVISIBLE (-5150 2500);
FORCEPROP 0 LASTPIN (-5225 2050) $PN 1
R 1
J 2
(-5235 2040);
DISPLAY 0.808511 (-5235 2040);
FORCEPROP 0 LASTPIN (-5325 2050) $PN 2
R 1
J 2
(-5335 2040);
DISPLAY 0.808511 (-5335 2040);
FORCEPROP 0 LASTPIN (-5425 2050) $PN 3
R 1
J 2
(-5435 2040);
DISPLAY 0.808511 (-5435 2040);
FORCEPROP 0 LASTPIN (-5525 2250) $PN 4
J 2
(-5535 2260);
DISPLAY 0.808511 (-5535 2260);
FORCEPROP 0 LASTPIN (-5325 2550) $PN 5
R 1
J 0
(-5335 2560);
DISPLAY 0.808511 (-5335 2560);
FORCEPROP 0 LAST ROOM HSC BOM2
J 0
(-5150 2500);
DISPLAY 0.680851 (-5150 2500);
FORCEPROP 2 LAST PART_TYPE SMLF
J 0
(-5150 2227);
DISPLAY 1.021277 (-5150 2227);
FORCEPROP 2 LAST VALUE PSMNR58-30YLH
J 0
(-5150 2277);
DISPLAY 0.723404 (-5150 2277);
PAINT SKYBLUE (-5150 2277);
FORCEPROP 1 LAST MATERIAL IC
J 0
(-5173 2450);
DISPLAY 0.723404 (-5173 2450);
PAINT SKYBLUE (-5173 2450);
FORCEPROP 1 LAST PART_NUMBER BAMNR580000
J 0
(-5173 2391);
DISPLAY 0.723404 (-5173 2391);
PAINT WHITE (-5173 2391);
DISPLAY INVISIBLE (-5173 2391);
FORCEPROP 1 LAST PATH I46
J 0
(-5325 2300);
DISPLAY 0.723404 (-5325 2300);
PAINT GREEN (-5325 2300);
DISPLAY INVISIBLE (-5325 2300);
FORCEPROP 2 LAST CDS_LIB pure_quanta
J 0
(-5325 2253);
DISPLAY INVISIBLE (-5325 2253);
FORCEPROP 1 LAST NEEDS_NO_SIZE TRUE
J 0
(-5325 2279);
DISPLAY 0.468085 (-5325 2279);
PAINT GREEN (-5325 2279);
DISPLAY INVISIBLE (-5325 2279);
FORCEPROP 1 LAST CDS_LMAN_SYM_OUTLINE -150,200,150,-200
J 0
(-5325 2278);
DISPLAY 0.468085 (-5325 2278);
PAINT GREEN (-5325 2278);
DISPLAY INVISIBLE (-5325 2278);
FORCEADD Q_RES..2
(-3975 1575);
FORCEPROP 1 LAST LOCATION PR2531
J 0
(-3930 1700);
DISPLAY 0.723404 (-3930 1700);
PAINT AQUA (-3930 1700);
FORCEPROP 0 LAST $SEC 1
J 0
(-3925 1750);
DISPLAY INVISIBLE (-3925 1750);
FORCEPROP 0 LAST CDS_SEC 1
J 0
(-3925 1750);
DISPLAY INVISIBLE (-3925 1750);
FORCEPROP 1 LASTPIN (-3975 1675) $PN 1
J 0
(-3970 1637);
DISPLAY 0.787234 (-3970 1637);
PAINT MONO (-3970 1637);
DISPLAY INVISIBLE (-3970 1637);
FORCEPROP 1 LASTPIN (-3975 1475) $PN 2
J 0
(-3970 1485);
DISPLAY 0.787234 (-3970 1485);
PAINT MONO (-3970 1485);
DISPLAY INVISIBLE (-3970 1485);
FORCEPROP 0 LAST ROOM HSC BOM2
J 0
(-3925 1750);
DISPLAY 0.680851 (-3925 1750);
FORCEPROP 1 LAST TOLERANCE 1%
J 0
(-3930 1600);
DISPLAY 0.723404 (-3930 1600);
PAINT SKYBLUE (-3930 1600);
FORCEPROP 1 LAST WATTAGE 1/16W
J 0
(-3935 1550);
DISPLAY 0.723404 (-3935 1550);
PAINT SKYBLUE (-3935 1550);
FORCEPROP 1 LAST PACK_TYPE 0402LF
J 0
(-3935 1400);
DISPLAY 0.723404 (-3935 1400);
PAINT SKYBLUE (-3935 1400);
FORCEPROP 1 LAST MATERIAL CHIP
J 0
(-3935 1500);
DISPLAY 0.723404 (-3935 1500);
PAINT SKYBLUE (-3935 1500);
FORCEPROP 1 LAST VALUE 10
J 0
(-3930 1650);
DISPLAY 0.723404 (-3930 1650);
PAINT SKYBLUE (-3930 1650);
FORCEPROP 1 LAST PART_NUMBER CS01002FB07
J 0
(-3935 1450);
DISPLAY 0.723404 (-3935 1450);
PAINT WHITE (-3935 1450);
DISPLAY INVISIBLE (-3935 1450);
FORCEPROP 1 LAST PATH I47
J 0
(-3925 1750);
DISPLAY 0.978723 (-3925 1750);
PAINT WHITE (-3925 1750);
DISPLAY INVISIBLE (-3925 1750);
FORCEPROP 2 LAST CDS_LIB pure_quanta
J 0
(-3975 1575);
DISPLAY INVISIBLE (-3975 1575);
FORCEADD OFFPAGE..2
R 2
(-4600 3200);
FORCEPROP 2 LAST $XR0 267 
J 0
(-4885 3200);
DISPLAY 0.638298 (-4885 3200);
PAINT MONO (-4885 3200);
FORCEPROP 2 LAST PATH I48
J 0
(-4550 3275);
DISPLAY 0.680851 (-4550 3275);
DISPLAY INVISIBLE (-4550 3275);
FORCEPROP 1 LAST COMMENT_BODY TRUE
J 2
(-4555 3105);
DISPLAY 0.872340 (-4555 3105);
PAINT GREEN (-4555 3105);
DISPLAY INVISIBLE (-4555 3105);
FORCEPROP 1 LAST OFFPAGE TRUE
J 2
(-4925 3075);
DISPLAY 0.872340 (-4925 3075);
PAINT AQUA (-4925 3075);
DISPLAY INVISIBLE (-4925 3075);
FORCEPROP 2 LAST CDS_LIB standard
J 0
(-4600 3200);
DISPLAY INVISIBLE (-4600 3200);
FORCEADD OFFPAGE..2
R 2
(-4600 3800);
FORCEPROP 2 LAST $XR0 267 
J 0
(-4885 3800);
DISPLAY 0.638298 (-4885 3800);
PAINT MONO (-4885 3800);
FORCEPROP 2 LAST PATH I49
J 0
(-4550 3875);
DISPLAY 0.680851 (-4550 3875);
DISPLAY INVISIBLE (-4550 3875);
FORCEPROP 1 LAST COMMENT_BODY TRUE
J 2
(-4555 3705);
DISPLAY 0.872340 (-4555 3705);
PAINT GREEN (-4555 3705);
DISPLAY INVISIBLE (-4555 3705);
FORCEPROP 1 LAST OFFPAGE TRUE
J 2
(-4925 3675);
DISPLAY 0.872340 (-4925 3675);
PAINT AQUA (-4925 3675);
DISPLAY INVISIBLE (-4925 3675);
FORCEPROP 2 LAST CDS_LIB standard
J 0
(-4600 3800);
DISPLAY INVISIBLE (-4600 3800);
FORCEADD Q_RES..1
(-8250 2850);
FORCEPROP 1 LAST LOCATION PR2523
J 0
(-8475 2900);
DISPLAY 0.723404 (-8475 2900);
PAINT AQUA (-8475 2900);
FORCEPROP 0 LAST $SEC 1
J 0
(-8150 2950);
DISPLAY 0.680851 (-8150 2950);
PAINT MONO (-8150 2950);
DISPLAY INVISIBLE (-8150 2950);
FORCEPROP 0 LAST CDS_SEC 1
J 0
(-8150 2950);
DISPLAY 1.021277 (-8150 2950);
DISPLAY INVISIBLE (-8150 2950);
FORCEPROP 1 LASTPIN (-8350 2850) $PN 1
J 0
(-8338 2862);
DISPLAY 0.787234 (-8338 2862);
PAINT MONO (-8338 2862);
FORCEPROP 1 LASTPIN (-8150 2850) $PN 2
J 0
(-8188 2862);
DISPLAY 0.787234 (-8188 2862);
PAINT MONO (-8188 2862);
FORCEPROP 0 LAST ROOM HSC BOM2
J 0
(-8850 2850);
DISPLAY 0.680851 (-8850 2850);
FORCEPROP 1 LAST MATERIAL CHIP
J 0
(-8150 2900);
DISPLAY 0.723404 (-8150 2900);
PAINT SKYBLUE (-8150 2900);
FORCEPROP 1 LAST TOLERANCE 1%
J 0
(-8225 2900);
DISPLAY 0.723404 (-8225 2900);
PAINT SKYBLUE (-8225 2900);
FORCEPROP 1 LAST VALUE 1
J 2
(-8275 2900);
DISPLAY 0.723404 (-8275 2900);
PAINT SKYBLUE (-8275 2900);
FORCEPROP 1 LAST PART_NUMBER CS-1002FB04
J 0
(-8225 2650);
DISPLAY 0.723404 (-8225 2650);
PAINT WHITE (-8225 2650);
DISPLAY INVISIBLE (-8225 2650);
FORCEPROP 1 LAST PATH I5
J 0
(-8300 3000);
DISPLAY 0.978723 (-8300 3000);
PAINT WHITE (-8300 3000);
DISPLAY INVISIBLE (-8300 3000);
FORCEPROP 2 LAST CDS_LIB pure_quanta
J 0
(-8250 2850);
DISPLAY INVISIBLE (-8250 2850);
FORCEPROP 1 LAST PACK_TYPE 0402LF
J 0
(-8325 2800);
DISPLAY 0.723404 (-8325 2800);
PAINT SKYBLUE (-8325 2800);
DISPLAY INVISIBLE (-8325 2800);
FORCEPROP 1 LAST WATTAGE 1/16W
J 2
(-7925 2800);
DISPLAY 0.723404 (-7925 2800);
PAINT SKYBLUE (-7925 2800);
DISPLAY INVISIBLE (-7925 2800);
FORCEADD OFFPAGE..2
R 2
(-4600 4375);
FORCEPROP 2 LAST $XR0 267 
J 0
(-4885 4375);
DISPLAY 0.638298 (-4885 4375);
PAINT MONO (-4885 4375);
FORCEPROP 2 LAST PATH I50
J 0
(-4550 4450);
DISPLAY 0.680851 (-4550 4450);
DISPLAY INVISIBLE (-4550 4450);
FORCEPROP 1 LAST COMMENT_BODY TRUE
J 2
(-4555 4280);
DISPLAY 0.872340 (-4555 4280);
PAINT GREEN (-4555 4280);
DISPLAY INVISIBLE (-4555 4280);
FORCEPROP 1 LAST OFFPAGE TRUE
J 2
(-4925 4250);
DISPLAY 0.872340 (-4925 4250);
PAINT AQUA (-4925 4250);
DISPLAY INVISIBLE (-4925 4250);
FORCEPROP 2 LAST CDS_LIB standard
J 0
(-4600 4375);
DISPLAY INVISIBLE (-4600 4375);
FORCEADD OFFPAGE..2
R 2
(-4600 4925);
FORCEPROP 2 LAST $XR0 267 
J 0
(-4885 4925);
DISPLAY 0.638298 (-4885 4925);
PAINT MONO (-4885 4925);
FORCEPROP 2 LAST PATH I51
J 0
(-4550 5000);
DISPLAY 0.680851 (-4550 5000);
DISPLAY INVISIBLE (-4550 5000);
FORCEPROP 1 LAST COMMENT_BODY TRUE
J 2
(-4555 4830);
DISPLAY 0.872340 (-4555 4830);
PAINT GREEN (-4555 4830);
DISPLAY INVISIBLE (-4555 4830);
FORCEPROP 1 LAST OFFPAGE TRUE
J 2
(-4925 4800);
DISPLAY 0.872340 (-4925 4800);
PAINT AQUA (-4925 4800);
DISPLAY INVISIBLE (-4925 4800);
FORCEPROP 2 LAST CDS_LIB standard
J 0
(-4600 4925);
DISPLAY INVISIBLE (-4600 4925);
FORCEADD Q_SP_RES4P..1
(-3525 3225);
FORCEPROP 1 LAST LOCATION PR2534
J 0
(-3775 3100);
DISPLAY 0.723404 (-3775 3100);
PAINT AQUA (-3775 3100);
FORCEPROP 0 LAST $SEC 1
J 0
(-3675 3725);
DISPLAY 0.680851 (-3675 3725);
PAINT MONO (-3675 3725);
DISPLAY INVISIBLE (-3675 3725);
FORCEPROP 0 LAST CDS_SEC 1
J 0
(-3675 3725);
DISPLAY 1.021277 (-3675 3725);
DISPLAY INVISIBLE (-3675 3725);
FORCEPROP 0 LASTPIN (-3725 3250) $PN 1A
J 2
(-3735 3260);
DISPLAY 0.680851 (-3735 3260);
PAINT MONO (-3735 3260);
FORCEPROP 0 LASTPIN (-3725 3200) $PN 1B
J 2
(-3735 3210);
DISPLAY 0.680851 (-3735 3210);
PAINT MONO (-3735 3210);
FORCEPROP 0 LASTPIN (-3325 3250) $PN 2A
J 0
(-3315 3260);
DISPLAY 0.680851 (-3315 3260);
PAINT MONO (-3315 3260);
FORCEPROP 0 LASTPIN (-3325 3200) $PN 2B
J 0
(-3315 3210);
DISPLAY 0.680851 (-3315 3210);
PAINT MONO (-3315 3210);
FORCEPROP 0 LAST ROOM HSC BOM2
J 0
(-3575 3100);
DISPLAY 0.553191 (-3575 3100);
FORCEPROP 2 LAST WATTAGE 4W
J 0
(-3275 3050);
DISPLAY 0.723404 (-3275 3050);
PAINT SKYBLUE (-3275 3050);
FORCEPROP 1 LAST MATERIAL CHIP
J 0
(-3775 2982);
DISPLAY 0.723404 (-3775 2982);
PAINT SKYBLUE (-3775 2982);
FORCEPROP 2 LAST TOLERANCE 1%
J 0
(-3275 3000);
DISPLAY 0.723404 (-3275 3000);
PAINT SKYBLUE (-3275 3000);
FORCEPROP 2 LAST VALUE 0.0003
J 0
(-3275 2950);
DISPLAY 0.723404 (-3275 2950);
PAINT SKYBLUE (-3275 2950);
FORCEPROP 2 LAST PART_TYPE SMLF
J 0
(-3275 3100);
DISPLAY 1.021277 (-3275 3100);
FORCEPROP 1 LAST PART_NUMBER SP_CS0000FFT09
J 0
(-3775 3042);
DISPLAY 0.723404 (-3775 3042);
PAINT WHITE (-3775 3042);
DISPLAY INVISIBLE (-3775 3042);
FORCEPROP 1 LAST PATH I52
J 0
(-3525 3225);
DISPLAY 0.723404 (-3525 3225);
PAINT GREEN (-3525 3225);
DISPLAY INVISIBLE (-3525 3225);
FORCEPROP 1 LAST CDS_LMAN_SYM_OUTLINE -150,75,150,-75
J 0
(-3525 3225);
DISPLAY 0.468085 (-3525 3225);
PAINT GREEN (-3525 3225);
DISPLAY INVISIBLE (-3525 3225);
FORCEPROP 2 LAST CDS_LIB pure_quanta
J 0
(-3525 3225);
DISPLAY INVISIBLE (-3525 3225);
FORCEPROP 1 LAST NEEDS_NO_SIZE TRUE
J 0
(-3375 3231);
DISPLAY 0.468085 (-3375 3231);
PAINT GREEN (-3375 3231);
DISPLAY INVISIBLE (-3375 3231);
FORCEADD Q_SP_RES4P..1
(-3525 3825);
FORCEPROP 1 LAST LOCATION PR2533
J 0
(-3650 3668);
DISPLAY 0.723404 (-3650 3668);
PAINT AQUA (-3650 3668);
FORCEPROP 0 LAST $SEC 1
J 0
(-3700 3725);
DISPLAY INVISIBLE (-3700 3725);
FORCEPROP 0 LAST CDS_SEC 1
J 0
(-3700 3725);
DISPLAY INVISIBLE (-3700 3725);
FORCEPROP 0 LASTPIN (-3725 3850) $PN 1A
J 2
(-3735 3860);
DISPLAY 0.808511 (-3735 3860);
FORCEPROP 0 LASTPIN (-3725 3800) $PN 1B
J 2
(-3735 3810);
DISPLAY 0.808511 (-3735 3810);
FORCEPROP 0 LASTPIN (-3325 3850) $PN 2A
J 0
(-3315 3860);
DISPLAY 0.808511 (-3315 3860);
FORCEPROP 0 LASTPIN (-3325 3800) $PN 2B
J 0
(-3315 3810);
DISPLAY 0.808511 (-3315 3810);
FORCEPROP 0 LAST ROOM HSC BOM2
J 0
(-3450 3675);
DISPLAY 0.680851 (-3450 3675);
FORCEPROP 2 LAST TOLERANCE 1%
J 0
(-3650 3375);
DISPLAY 0.723404 (-3650 3375);
PAINT SKYBLUE (-3650 3375);
FORCEPROP 2 LAST WATTAGE 4W
J 0
(-3650 3425);
DISPLAY 0.723404 (-3650 3425);
PAINT SKYBLUE (-3650 3425);
FORCEPROP 2 LAST PART_TYPE SMLF
J 0
(-3650 3475);
DISPLAY 1.021277 (-3650 3475);
FORCEPROP 1 LAST MATERIAL CHIP
J 0
(-3650 3550);
DISPLAY 0.723404 (-3650 3550);
PAINT SKYBLUE (-3650 3550);
FORCEPROP 2 LAST VALUE 0.0003
J 0
(-3650 3325);
DISPLAY 0.723404 (-3650 3325);
PAINT SKYBLUE (-3650 3325);
FORCEPROP 1 LAST PART_NUMBER SP_CS0000FFT09
J 0
(-3650 3610);
DISPLAY 0.723404 (-3650 3610);
PAINT WHITE (-3650 3610);
DISPLAY INVISIBLE (-3650 3610);
FORCEPROP 1 LAST PATH I53
J 0
(-3525 3825);
DISPLAY 0.723404 (-3525 3825);
PAINT GREEN (-3525 3825);
DISPLAY INVISIBLE (-3525 3825);
FORCEPROP 1 LAST NEEDS_NO_SIZE TRUE
J 0
(-3375 3831);
DISPLAY 0.468085 (-3375 3831);
PAINT GREEN (-3375 3831);
DISPLAY INVISIBLE (-3375 3831);
FORCEPROP 1 LAST CDS_LMAN_SYM_OUTLINE -150,75,150,-75
J 0
(-3525 3825);
DISPLAY 0.468085 (-3525 3825);
PAINT GREEN (-3525 3825);
DISPLAY INVISIBLE (-3525 3825);
FORCEPROP 2 LAST CDS_LIB pure_quanta
J 0
(-3525 3825);
DISPLAY INVISIBLE (-3525 3825);
FORCEADD Q_SP_RES4P..1
(-3525 4400);
FORCEPROP 1 LAST LOCATION PR2532
J 0
(-3675 4070);
DISPLAY 0.723404 (-3675 4070);
PAINT AQUA (-3675 4070);
FORCEPROP 0 LAST $SEC 1
J 0
(-3675 4850);
DISPLAY INVISIBLE (-3675 4850);
FORCEPROP 0 LAST CDS_SEC 1
J 0
(-3675 4850);
DISPLAY INVISIBLE (-3675 4850);
FORCEPROP 0 LASTPIN (-3725 4425) $PN 1A
J 2
(-3735 4439);
DISPLAY 0.723404 (-3735 4439);
FORCEPROP 0 LASTPIN (-3725 4375) $PN 1B
J 2
(-3735 4389);
DISPLAY 0.723404 (-3735 4389);
FORCEPROP 0 LASTPIN (-3325 4425) $PN 2A
J 0
(-3315 4439);
DISPLAY 0.723404 (-3315 4439);
FORCEPROP 0 LASTPIN (-3325 4375) $PN 2B
J 0
(-3315 4389);
DISPLAY 0.723404 (-3315 4389);
FORCEPROP 1 LAST MATERIAL CHIP
J 0
(-3675 3952);
DISPLAY 0.723404 (-3675 3952);
PAINT SKYBLUE (-3675 3952);
FORCEPROP 0 LAST ROOM HSC BOM2
J 0
(-3450 4075);
DISPLAY 0.680851 (-3450 4075);
FORCEPROP 2 LAST VALUE 0.0003
J 0
(-3675 4125);
DISPLAY 0.723404 (-3675 4125);
PAINT SKYBLUE (-3675 4125);
FORCEPROP 2 LAST WATTAGE 4W
J 0
(-3675 4225);
DISPLAY 0.723404 (-3675 4225);
PAINT SKYBLUE (-3675 4225);
FORCEPROP 2 LAST PART_TYPE SMLF
J 0
(-3675 4275);
DISPLAY 1.021277 (-3675 4275);
FORCEPROP 2 LAST TOLERANCE 1%
J 0
(-3675 4175);
DISPLAY 0.723404 (-3675 4175);
PAINT SKYBLUE (-3675 4175);
FORCEPROP 1 LAST PART_NUMBER SP_CS0000FFT09
J 0
(-3675 4012);
DISPLAY 0.723404 (-3675 4012);
PAINT WHITE (-3675 4012);
DISPLAY INVISIBLE (-3675 4012);
FORCEPROP 1 LAST PATH I54
J 0
(-3525 4400);
DISPLAY 0.723404 (-3525 4400);
PAINT GREEN (-3525 4400);
DISPLAY INVISIBLE (-3525 4400);
FORCEPROP 1 LAST NEEDS_NO_SIZE TRUE
J 0
(-3375 4406);
DISPLAY 0.468085 (-3375 4406);
PAINT GREEN (-3375 4406);
DISPLAY INVISIBLE (-3375 4406);
FORCEPROP 1 LAST CDS_LMAN_SYM_OUTLINE -150,75,150,-75
J 0
(-3525 4400);
DISPLAY 0.468085 (-3525 4400);
PAINT GREEN (-3525 4400);
DISPLAY INVISIBLE (-3525 4400);
FORCEPROP 2 LAST CDS_LIB pure_quanta
J 0
(-3525 4400);
DISPLAY INVISIBLE (-3525 4400);
FORCEADD Q_SP_RES4P..1
(-3500 4950);
FORCEPROP 1 LAST LOCATION PR6001
J 0
(-3650 4625);
DISPLAY 0.723404 (-3650 4625);
PAINT AQUA (-3650 4625);
FORCEPROP 2 LAST SEC 1
J 0
(-3650 4418);
DISPLAY 0.680851 (-3650 4418);
PAINT MONO (-3650 4418);
DISPLAY INVISIBLE (-3650 4418);
FORCEPROP 2 LASTPIN (-3700 4975) $PN 1A
J 2
(-3710 4933);
DISPLAY 0.680851 (-3710 4933);
PAINT MONO (-3710 4933);
FORCEPROP 2 LASTPIN (-3700 4925) $PN 1B
J 2
(-3710 4883);
DISPLAY 0.680851 (-3710 4883);
PAINT MONO (-3710 4883);
FORCEPROP 2 LASTPIN (-3300 4975) $PN 2A
J 0
(-3290 4933);
DISPLAY 0.680851 (-3290 4933);
PAINT MONO (-3290 4933);
FORCEPROP 2 LASTPIN (-3300 4925) $PN 2B
J 0
(-3290 4883);
DISPLAY 0.680851 (-3290 4883);
PAINT MONO (-3290 4883);
FORCEPROP 2 LAST TOLERANCE 1%
J 0
(-3650 4730);
DISPLAY 0.723404 (-3650 4730);
PAINT SKYBLUE (-3650 4730);
FORCEPROP 0 LAST ROOM HSC BOM2
J 0
(-3450 4625);
DISPLAY 0.680851 (-3450 4625);
FORCEPROP 2 LAST VALUE 0.0003
J 0
(-3650 4680);
DISPLAY 0.723404 (-3650 4680);
PAINT SKYBLUE (-3650 4680);
FORCEPROP 2 LAST PART_TYPE SMLF
J 0
(-3650 4830);
DISPLAY 1.021277 (-3650 4830);
FORCEPROP 1 LAST MATERIAL CHIP
J 0
(-3650 4507);
DISPLAY 0.723404 (-3650 4507);
PAINT SKYBLUE (-3650 4507);
FORCEPROP 2 LAST WATTAGE 4W
J 0
(-3650 4780);
DISPLAY 0.723404 (-3650 4780);
PAINT SKYBLUE (-3650 4780);
FORCEPROP 1 LAST PART_NUMBER SP_CS0000FFT09
J 0
(-3650 4567);
DISPLAY 0.723404 (-3650 4567);
PAINT WHITE (-3650 4567);
DISPLAY INVISIBLE (-3650 4567);
FORCEPROP 1 LAST PATH I55
J 0
(-3500 4950);
DISPLAY 0.723404 (-3500 4950);
PAINT GREEN (-3500 4950);
DISPLAY INVISIBLE (-3500 4950);
FORCEPROP 2 LAST SEC_TYPE 
J 0
(-3650 4402);
DISPLAY 1.021277 (-3650 4402);
DISPLAY INVISIBLE (-3650 4402);
FORCEPROP 2 LAST CDS_LIB pure_quanta
J 0
(-3500 4903);
DISPLAY INVISIBLE (-3500 4903);
FORCEPROP 1 LAST CDS_LMAN_SYM_OUTLINE -150,75,150,-75
J 0
(-3500 4928);
DISPLAY 0.468085 (-3500 4928);
PAINT GREEN (-3500 4928);
DISPLAY INVISIBLE (-3500 4928);
FORCEPROP 1 LAST NEEDS_NO_SIZE TRUE
J 0
(-3350 4956);
DISPLAY 0.468085 (-3350 4956);
PAINT GREEN (-3350 4956);
DISPLAY INVISIBLE (-3350 4956);
FORCEADD UNIVERSAL_POWER..1
(-4875 5350);
FORCEPROP 3 LASTPIN (-4875 5300) SIG_NAME P12V_PSU\g
J 0
(-4865 5310);
DISPLAY 0.659574 (-4865 5310);
PAINT MONO (-4865 5310);
DISPLAY INVISIBLE (-4865 5310);
FORCEPROP 1 LAST HDL_POWER P12V_PSU
J 1
(-4875 5400);
DISPLAY 0.723404 (-4875 5400);
PAINT GREEN (-4875 5400);
FORCEPROP 1 LAST PATH I56
J 0
(-4825 5375);
DISPLAY 0.872340 (-4825 5375);
PAINT AQUA (-4825 5375);
DISPLAY INVISIBLE (-4825 5375);
FORCEPROP 2 LAST ROOM AUX_SW
J 0
(-4875 5450);
DISPLAY 0.617021 (-4875 5450);
DISPLAY INVISIBLE (-4875 5450);
FORCEPROP 2 LAST BOM_COST MIO_VRD_SB
J 0
(-4875 5450);
DISPLAY 0.617021 (-4875 5450);
PAINT PURPLE (-4875 5450);
DISPLAY INVISIBLE (-4875 5450);
FORCEPROP 2 LAST CDS_LIB pure_quanta_power
J 0
(-4875 5350);
DISPLAY INVISIBLE (-4875 5350);
FORCEADD OFFPAGE..2
R 2
(-4575 5275);
FORCEPROP 2 LAST $XR0 267 
J 0
(-4860 5275);
DISPLAY 0.638298 (-4860 5275);
PAINT MONO (-4860 5275);
FORCEPROP 2 LAST $XR1 268 
J 0
(-4980 5275);
DISPLAY 0.638298 (-4980 5275);
PAINT MONO (-4980 5275);
FORCEPROP 2 LAST PATH I57
J 0
(-4525 5350);
DISPLAY 0.680851 (-4525 5350);
DISPLAY INVISIBLE (-4525 5350);
FORCEPROP 1 LAST COMMENT_BODY TRUE
J 2
(-4530 5180);
DISPLAY 0.872340 (-4530 5180);
PAINT GREEN (-4530 5180);
DISPLAY INVISIBLE (-4530 5180);
FORCEPROP 1 LAST OFFPAGE TRUE
J 2
(-4900 5150);
DISPLAY 0.872340 (-4900 5150);
PAINT AQUA (-4900 5150);
DISPLAY INVISIBLE (-4900 5150);
FORCEPROP 2 LAST CDS_LIB standard
J 0
(-4575 5275);
DISPLAY INVISIBLE (-4575 5275);
FORCEADD GND..1
(-475 875);
FORCEPROP 3 LASTPIN (-475 925) SIG_NAME GND\g
J 0
(-465 935);
DISPLAY 0.659574 (-465 935);
PAINT MONO (-465 935);
DISPLAY INVISIBLE (-465 935);
FORCEPROP 1 LAST PATH I59
J 0
(-400 875);
DISPLAY 0.872340 (-400 875);
PAINT AQUA (-400 875);
DISPLAY INVISIBLE (-400 875);
FORCEPROP 1 LAST HDL_POWER GND
J 0
(-475 1025);
DISPLAY 1.170213 (-475 1025);
PAINT GREEN (-475 1025);
DISPLAY INVISIBLE (-475 1025);
FORCEPROP 2 LAST CDS_LIB pure_quanta_power
J 0
(-475 875);
DISPLAY INVISIBLE (-475 875);
FORCEPROP 2 LAST ROOM VR_DDR1_POWER_STAGE
J 0
(-700 950);
DISPLAY INVISIBLE (-700 950);
FORCEPROP 1 LAST SIZE 1B
J 0
(-400 825);
DISPLAY 0.872340 (-400 825);
PAINT AQUA (-400 825);
DISPLAY INVISIBLE (-400 825);
FORCEADD Q_RES..1
(-8250 3050);
FORCEPROP 1 LAST LOCATION PR2521
J 0
(-8475 3100);
DISPLAY 0.723404 (-8475 3100);
PAINT AQUA (-8475 3100);
FORCEPROP 0 LAST $SEC 1
J 0
(-7775 3100);
DISPLAY INVISIBLE (-7775 3100);
FORCEPROP 0 LAST CDS_SEC 1
J 0
(-7775 3100);
DISPLAY INVISIBLE (-7775 3100);
FORCEPROP 1 LASTPIN (-8350 3050) $PN 1
J 0
(-8338 3062);
DISPLAY 0.723404 (-8338 3062);
PAINT MONO (-8338 3062);
FORCEPROP 1 LASTPIN (-8150 3050) $PN 2
J 0
(-8188 3062);
DISPLAY 0.723404 (-8188 3062);
PAINT MONO (-8188 3062);
FORCEPROP 0 LAST ROOM HSC BOM2
J 0
(-8850 3050);
DISPLAY 0.680851 (-8850 3050);
FORCEPROP 1 LAST TOLERANCE 1%
J 0
(-8225 3100);
DISPLAY 0.723404 (-8225 3100);
PAINT SKYBLUE (-8225 3100);
FORCEPROP 1 LAST VALUE 1
J 2
(-8275 3100);
DISPLAY 0.723404 (-8275 3100);
PAINT SKYBLUE (-8275 3100);
FORCEPROP 1 LAST MATERIAL CHIP
J 0
(-8150 3100);
DISPLAY 0.723404 (-8150 3100);
PAINT SKYBLUE (-8150 3100);
FORCEPROP 1 LAST PART_NUMBER CS-1002FB04
J 0
(-8225 2850);
DISPLAY 0.723404 (-8225 2850);
PAINT WHITE (-8225 2850);
DISPLAY INVISIBLE (-8225 2850);
FORCEPROP 1 LAST PATH I6
J 0
(-8300 3200);
DISPLAY 0.978723 (-8300 3200);
PAINT WHITE (-8300 3200);
DISPLAY INVISIBLE (-8300 3200);
FORCEPROP 2 LAST CDS_LIB pure_quanta
J 0
(-8250 3050);
DISPLAY INVISIBLE (-8250 3050);
FORCEPROP 1 LAST PACK_TYPE 0402LF
J 0
(-8325 3000);
DISPLAY 0.723404 (-8325 3000);
PAINT SKYBLUE (-8325 3000);
DISPLAY INVISIBLE (-8325 3000);
FORCEPROP 1 LAST WATTAGE 1/16W
J 2
(-7925 3000);
DISPLAY 0.723404 (-7925 3000);
PAINT SKYBLUE (-7925 3000);
DISPLAY INVISIBLE (-7925 3000);
FORCEADD Q_RES..2
(-3125 1575);
FORCEPROP 1 LAST LOCATION PR2535
J 0
(-3080 1700);
DISPLAY 0.723404 (-3080 1700);
PAINT AQUA (-3080 1700);
FORCEPROP 0 LAST $SEC 1
J 0
(-3075 1750);
DISPLAY 0.680851 (-3075 1750);
PAINT MONO (-3075 1750);
DISPLAY INVISIBLE (-3075 1750);
FORCEPROP 0 LAST CDS_SEC 1
J 0
(-3075 1750);
DISPLAY 1.021277 (-3075 1750);
DISPLAY INVISIBLE (-3075 1750);
FORCEPROP 1 LASTPIN (-3125 1675) $PN 1
J 0
(-3120 1637);
DISPLAY 0.787234 (-3120 1637);
PAINT MONO (-3120 1637);
FORCEPROP 1 LASTPIN (-3125 1475) $PN 2
J 0
(-3120 1485);
DISPLAY 0.787234 (-3120 1485);
PAINT MONO (-3120 1485);
FORCEPROP 0 LAST ROOM HSC BOM2
J 0
(-3075 1750);
DISPLAY 0.680851 (-3075 1750);
FORCEPROP 1 LAST WATTAGE 1/16W
J 0
(-3085 1550);
DISPLAY 0.723404 (-3085 1550);
PAINT SKYBLUE (-3085 1550);
FORCEPROP 1 LAST MATERIAL CHIP
J 0
(-3085 1500);
DISPLAY 0.723404 (-3085 1500);
PAINT SKYBLUE (-3085 1500);
FORCEPROP 1 LAST PACK_TYPE 0402LF
J 0
(-3085 1400);
DISPLAY 0.723404 (-3085 1400);
PAINT SKYBLUE (-3085 1400);
FORCEPROP 1 LAST VALUE 10
J 0
(-3080 1650);
DISPLAY 0.723404 (-3080 1650);
PAINT SKYBLUE (-3080 1650);
FORCEPROP 1 LAST TOLERANCE 1%
J 0
(-3080 1600);
DISPLAY 0.723404 (-3080 1600);
PAINT SKYBLUE (-3080 1600);
FORCEPROP 1 LAST PART_NUMBER CS01002FB07
J 0
(-3085 1450);
DISPLAY 0.723404 (-3085 1450);
PAINT WHITE (-3085 1450);
DISPLAY INVISIBLE (-3085 1450);
FORCEPROP 1 LAST PATH I60
J 0
(-3075 1750);
DISPLAY 0.978723 (-3075 1750);
PAINT WHITE (-3075 1750);
DISPLAY INVISIBLE (-3075 1750);
FORCEPROP 2 LAST CDS_LIB pure_quanta
J 0
(-3125 1575);
DISPLAY INVISIBLE (-3125 1575);
FORCEADD MOSFET_NCH_1D3S..1
R 6
(-2700 2350);
FORCEPROP 1 LAST LOCATION PPQ1
J 0
(-2548 2384);
DISPLAY 0.723404 (-2548 2384);
PAINT AQUA (-2548 2384);
FORCEPROP 2 LAST SEC 1
J 0
(-2525 2550);
DISPLAY 0.680851 (-2525 2550);
PAINT MONO (-2525 2550);
DISPLAY INVISIBLE (-2525 2550);
FORCEPROP 2 LASTPIN (-2600 2100) $PN 1
R 1
J 2
(-2610 2085);
DISPLAY 0.680851 (-2610 2085);
PAINT MONO (-2610 2085);
FORCEPROP 2 LASTPIN (-2700 2100) $PN 2
R 1
J 2
(-2710 2085);
DISPLAY 0.680851 (-2710 2085);
PAINT MONO (-2710 2085);
FORCEPROP 2 LASTPIN (-2800 2100) $PN 3
R 1
J 2
(-2810 2085);
DISPLAY 0.680851 (-2810 2085);
PAINT MONO (-2810 2085);
FORCEPROP 2 LASTPIN (-2900 2300) $PN 4
J 2
(-2910 2310);
DISPLAY 0.680851 (-2910 2310);
PAINT MONO (-2910 2310);
FORCEPROP 2 LASTPIN (-2700 2600) $PN 5
R 1
J 0
(-2710 2610);
DISPLAY 0.680851 (-2710 2610);
PAINT MONO (-2710 2610);
FORCEPROP 0 LAST ROOM HSC BOM2
J 0
(-2525 2550);
DISPLAY 0.680851 (-2525 2550);
FORCEPROP 2 LAST VALUE PSMNR58-30YLH
J 0
(-2525 2327);
DISPLAY 0.723404 (-2525 2327);
PAINT SKYBLUE (-2525 2327);
FORCEPROP 2 LAST PART_TYPE SMLF
J 0
(-2525 2277);
DISPLAY 1.021277 (-2525 2277);
FORCEPROP 1 LAST MATERIAL IC
J 0
(-2548 2500);
DISPLAY 0.723404 (-2548 2500);
PAINT SKYBLUE (-2548 2500);
FORCEPROP 1 LAST PART_NUMBER BAMNR580000
J 0
(-2548 2441);
DISPLAY 0.723404 (-2548 2441);
PAINT WHITE (-2548 2441);
DISPLAY INVISIBLE (-2548 2441);
FORCEPROP 1 LAST PATH I61
J 0
(-2700 2350);
DISPLAY 0.723404 (-2700 2350);
PAINT GREEN (-2700 2350);
DISPLAY INVISIBLE (-2700 2350);
FORCEPROP 2 LAST SEC_TYPE 
J 0
(-2525 2550);
DISPLAY 1.021277 (-2525 2550);
DISPLAY INVISIBLE (-2525 2550);
FORCEPROP 1 LAST NEEDS_NO_SIZE TRUE
J 0
(-2700 2329);
DISPLAY 0.468085 (-2700 2329);
PAINT GREEN (-2700 2329);
DISPLAY INVISIBLE (-2700 2329);
FORCEPROP 1 LAST CDS_LMAN_SYM_OUTLINE -150,200,150,-200
J 0
(-2700 2350);
DISPLAY 0.468085 (-2700 2350);
PAINT GREEN (-2700 2350);
DISPLAY INVISIBLE (-2700 2350);
FORCEPROP 2 LAST CDS_LIB pure_quanta
J 0
(-2700 2350);
DISPLAY INVISIBLE (-2700 2350);
FORCEADD Q_RES..2
(-2250 1575);
FORCEPROP 1 LAST LOCATION PR2536
J 0
(-2205 1700);
DISPLAY 0.723404 (-2205 1700);
PAINT AQUA (-2205 1700);
FORCEPROP 0 LAST $SEC 1
J 0
(-2200 1750);
DISPLAY 0.680851 (-2200 1750);
PAINT MONO (-2200 1750);
DISPLAY INVISIBLE (-2200 1750);
FORCEPROP 0 LAST CDS_SEC 1
J 0
(-2200 1750);
DISPLAY 1.021277 (-2200 1750);
DISPLAY INVISIBLE (-2200 1750);
FORCEPROP 1 LASTPIN (-2250 1675) $PN 1
J 0
(-2245 1637);
DISPLAY 0.787234 (-2245 1637);
PAINT MONO (-2245 1637);
FORCEPROP 1 LASTPIN (-2250 1475) $PN 2
J 0
(-2245 1485);
DISPLAY 0.787234 (-2245 1485);
PAINT MONO (-2245 1485);
FORCEPROP 1 LAST MATERIAL CHIP
J 0
(-2210 1500);
DISPLAY 0.723404 (-2210 1500);
PAINT SKYBLUE (-2210 1500);
FORCEPROP 1 LAST PACK_TYPE 0402LF
J 0
(-2210 1400);
DISPLAY 0.723404 (-2210 1400);
PAINT SKYBLUE (-2210 1400);
FORCEPROP 0 LAST ROOM HSC BOM2
J 0
(-2200 1750);
DISPLAY 0.680851 (-2200 1750);
FORCEPROP 1 LAST WATTAGE 1/16W
J 0
(-2210 1550);
DISPLAY 0.723404 (-2210 1550);
PAINT SKYBLUE (-2210 1550);
FORCEPROP 1 LAST TOLERANCE 1%
J 0
(-2205 1600);
DISPLAY 0.723404 (-2205 1600);
PAINT SKYBLUE (-2205 1600);
FORCEPROP 1 LAST VALUE 10
J 0
(-2205 1650);
DISPLAY 0.723404 (-2205 1650);
PAINT SKYBLUE (-2205 1650);
FORCEPROP 1 LAST PART_NUMBER CS01002FB07
J 0
(-2210 1450);
DISPLAY 0.723404 (-2210 1450);
PAINT WHITE (-2210 1450);
DISPLAY INVISIBLE (-2210 1450);
FORCEPROP 1 LAST PATH I62
J 0
(-2200 1750);
DISPLAY 0.978723 (-2200 1750);
PAINT WHITE (-2200 1750);
DISPLAY INVISIBLE (-2200 1750);
FORCEPROP 2 LAST CDS_LIB pure_quanta
J 0
(-2250 1575);
DISPLAY INVISIBLE (-2250 1575);
FORCEADD Q_CAP..1
(-1650 1575);
FORCEPROP 1 LAST LOCATION PC1750
J 0
(-1600 1675);
DISPLAY 0.978723 (-1600 1675);
FORCEPROP 0 LAST $SEC 1
J 0
(-1600 1725);
DISPLAY 0.680851 (-1600 1725);
PAINT MONO (-1600 1725);
DISPLAY INVISIBLE (-1600 1725);
FORCEPROP 0 LAST CDS_SEC 1
J 0
(-1600 1725);
DISPLAY 1.021277 (-1600 1725);
DISPLAY INVISIBLE (-1600 1725);
FORCEPROP 1 LASTPIN (-1650 1675) $PN 1
J 0
(-1640 1655);
DISPLAY 0.787234 (-1640 1655);
PAINT MONO (-1640 1655);
FORCEPROP 1 LASTPIN (-1650 1475) $PN 2
J 0
(-1640 1455);
DISPLAY 0.787234 (-1640 1455);
PAINT MONO (-1640 1455);
FORCEPROP 0 LAST ROOM HSC BOM2
J 0
(-1600 1725);
DISPLAY 0.680851 (-1600 1725);
FORCEPROP 1 LAST VALUE 33NF
J 0
(-1600 1625);
DISPLAY 0.723404 (-1600 1625);
PAINT SKYBLUE (-1600 1625);
FORCEPROP 1 LAST VOLTAGE 25V
J 0
(-1600 1575);
DISPLAY 0.723404 (-1600 1575);
PAINT SKYBLUE (-1600 1575);
FORCEPROP 1 LAST TOLERANCE 10%
J 0
(-1600 1525);
DISPLAY 0.723404 (-1600 1525);
PAINT SKYBLUE (-1600 1525);
FORCEPROP 1 LAST MATERIAL EMPTY
J 0
(-1600 1475);
DISPLAY 0.723404 (-1600 1475);
PAINT RED (-1600 1475);
FORCEPROP 1 LAST PACK_TYPE C0402
J 0
(-1600 1375);
DISPLAY 0.723404 (-1600 1375);
PAINT SKYBLUE (-1600 1375);
FORCEPROP 1 LAST PART_NUMBER CH3334K1B00
J 0
(-1600 1425);
DISPLAY 0.723404 (-1600 1425);
PAINT WHITE (-1600 1425);
DISPLAY INVISIBLE (-1600 1425);
FORCEPROP 1 LAST PATH I63
J 0
(-1600 1725);
DISPLAY 0.978723 (-1600 1725);
PAINT WHITE (-1600 1725);
DISPLAY INVISIBLE (-1600 1725);
FORCEPROP 2 LAST CDS_LIB pure_quanta
J 0
(-1650 1575);
DISPLAY INVISIBLE (-1650 1575);
FORCEADD MOSFET_NCH_1D3S..1
R 6
(-1825 2375);
FORCEPROP 1 LAST LOCATION PPQ2
J 0
(-1673 2409);
DISPLAY 0.723404 (-1673 2409);
PAINT AQUA (-1673 2409);
FORCEPROP 2 LAST SEC 1
J 0
(-1650 2575);
DISPLAY 0.680851 (-1650 2575);
PAINT MONO (-1650 2575);
DISPLAY INVISIBLE (-1650 2575);
FORCEPROP 2 LASTPIN (-1725 2125) $PN 1
R 1
J 2
(-1735 2115);
DISPLAY 0.680851 (-1735 2115);
PAINT MONO (-1735 2115);
FORCEPROP 2 LASTPIN (-1825 2125) $PN 2
R 1
J 2
(-1835 2115);
DISPLAY 0.680851 (-1835 2115);
PAINT MONO (-1835 2115);
FORCEPROP 2 LASTPIN (-1925 2125) $PN 3
R 1
J 2
(-1935 2115);
DISPLAY 0.680851 (-1935 2115);
PAINT MONO (-1935 2115);
FORCEPROP 2 LASTPIN (-2025 2325) $PN 4
J 2
(-2035 2335);
DISPLAY 0.680851 (-2035 2335);
PAINT MONO (-2035 2335);
FORCEPROP 2 LASTPIN (-1825 2625) $PN 5
R 1
J 0
(-1835 2635);
DISPLAY 0.680851 (-1835 2635);
PAINT MONO (-1835 2635);
FORCEPROP 2 LAST PART_TYPE SMLF
J 0
(-1650 2302);
DISPLAY 1.021277 (-1650 2302);
FORCEPROP 2 LAST VALUE PSMNR58-30YLH
J 0
(-1650 2352);
DISPLAY 0.723404 (-1650 2352);
PAINT SKYBLUE (-1650 2352);
FORCEPROP 0 LAST ROOM HSC BOM2
J 0
(-1650 2575);
DISPLAY 0.680851 (-1650 2575);
FORCEPROP 1 LAST MATERIAL IC
J 0
(-1673 2525);
DISPLAY 0.723404 (-1673 2525);
PAINT SKYBLUE (-1673 2525);
FORCEPROP 1 LAST PART_NUMBER BAMNR580000
J 0
(-1673 2466);
DISPLAY 0.723404 (-1673 2466);
PAINT WHITE (-1673 2466);
DISPLAY INVISIBLE (-1673 2466);
FORCEPROP 1 LAST PATH I64
J 0
(-1825 2375);
DISPLAY 0.723404 (-1825 2375);
PAINT GREEN (-1825 2375);
DISPLAY INVISIBLE (-1825 2375);
FORCEPROP 2 LAST SEC_TYPE 
J 0
(-1650 2575);
DISPLAY 1.021277 (-1650 2575);
DISPLAY INVISIBLE (-1650 2575);
FORCEPROP 2 LAST CDS_LIB pure_quanta
J 0
(-1825 2375);
DISPLAY INVISIBLE (-1825 2375);
FORCEPROP 1 LAST CDS_LMAN_SYM_OUTLINE -150,200,150,-200
J 0
(-1825 2375);
DISPLAY 0.468085 (-1825 2375);
PAINT GREEN (-1825 2375);
DISPLAY INVISIBLE (-1825 2375);
FORCEPROP 1 LAST NEEDS_NO_SIZE TRUE
J 0
(-1825 2354);
DISPLAY 0.468085 (-1825 2354);
PAINT GREEN (-1825 2354);
DISPLAY INVISIBLE (-1825 2354);
FORCEADD OFFPAGE..4
R 2
(-1400 2800);
FORCEPROP 2 LAST $XR0 268 
J 0
(-1682 2800);
DISPLAY 0.638298 (-1682 2800);
PAINT MONO (-1682 2800);
FORCEPROP 2 LAST PATH I65
J 0
(-1350 2875);
DISPLAY 0.680851 (-1350 2875);
DISPLAY INVISIBLE (-1350 2875);
FORCEPROP 1 LAST COMMENT_BODY TRUE
J 2
(-1375 2700);
DISPLAY 0.872340 (-1375 2700);
PAINT GREEN (-1375 2700);
DISPLAY INVISIBLE (-1375 2700);
FORCEPROP 1 LAST OFFPAGE TRUE
J 2
(-1725 2675);
DISPLAY 0.872340 (-1725 2675);
PAINT GREEN (-1725 2675);
DISPLAY INVISIBLE (-1725 2675);
FORCEPROP 2 LAST CDS_LIB standard
J 0
(-1400 2800);
DISPLAY INVISIBLE (-1400 2800);
FORCEADD OFFPAGE..2
(-2300 3200);
FORCEPROP 2 LAST $XR0 267 
J 0
(-2111 3200);
DISPLAY 0.638298 (-2111 3200);
PAINT MONO (-2111 3200);
FORCEPROP 2 LAST PATH I66
J 0
(-2125 3275);
DISPLAY 0.680851 (-2125 3275);
DISPLAY INVISIBLE (-2125 3275);
FORCEPROP 1 LAST COMMENT_BODY TRUE
J 0
(-2345 3105);
DISPLAY 0.872340 (-2345 3105);
PAINT GREEN (-2345 3105);
DISPLAY INVISIBLE (-2345 3105);
FORCEPROP 1 LAST OFFPAGE TRUE
J 0
(-1975 3075);
DISPLAY 0.872340 (-1975 3075);
PAINT AQUA (-1975 3075);
DISPLAY INVISIBLE (-1975 3075);
FORCEPROP 2 LAST CDS_LIB standard
J 0
(-2300 3200);
DISPLAY INVISIBLE (-2300 3200);
FORCEADD OFFPAGE..2
(-2300 3800);
FORCEPROP 2 LAST $XR0 267 
J 0
(-2111 3800);
DISPLAY 0.638298 (-2111 3800);
PAINT MONO (-2111 3800);
FORCEPROP 2 LAST PATH I67
J 0
(-2125 3875);
DISPLAY 0.680851 (-2125 3875);
DISPLAY INVISIBLE (-2125 3875);
FORCEPROP 1 LAST COMMENT_BODY TRUE
J 0
(-2345 3705);
DISPLAY 0.872340 (-2345 3705);
PAINT GREEN (-2345 3705);
DISPLAY INVISIBLE (-2345 3705);
FORCEPROP 1 LAST OFFPAGE TRUE
J 0
(-1975 3675);
DISPLAY 0.872340 (-1975 3675);
PAINT AQUA (-1975 3675);
DISPLAY INVISIBLE (-1975 3675);
FORCEPROP 2 LAST CDS_LIB standard
J 0
(-2300 3800);
DISPLAY INVISIBLE (-2300 3800);
FORCEADD OFFPAGE..2
(-2300 4375);
FORCEPROP 2 LAST $XR0 267 
J 0
(-2111 4375);
DISPLAY 0.638298 (-2111 4375);
PAINT MONO (-2111 4375);
FORCEPROP 2 LAST PATH I68
J 0
(-2125 4450);
DISPLAY 0.680851 (-2125 4450);
DISPLAY INVISIBLE (-2125 4450);
FORCEPROP 1 LAST COMMENT_BODY TRUE
J 0
(-2345 4280);
DISPLAY 0.872340 (-2345 4280);
PAINT GREEN (-2345 4280);
DISPLAY INVISIBLE (-2345 4280);
FORCEPROP 1 LAST OFFPAGE TRUE
J 0
(-1975 4250);
DISPLAY 0.872340 (-1975 4250);
PAINT AQUA (-1975 4250);
DISPLAY INVISIBLE (-1975 4250);
FORCEPROP 2 LAST CDS_LIB standard
J 0
(-2300 4375);
DISPLAY INVISIBLE (-2300 4375);
FORCEADD OFFPAGE..2
(-2275 4925);
FORCEPROP 2 LAST $XR0 267 
J 0
(-2086 4925);
DISPLAY 0.638298 (-2086 4925);
PAINT MONO (-2086 4925);
FORCEPROP 2 LAST PATH I69
J 0
(-2100 5000);
DISPLAY 0.680851 (-2100 5000);
DISPLAY INVISIBLE (-2100 5000);
FORCEPROP 1 LAST COMMENT_BODY TRUE
J 0
(-2320 4830);
DISPLAY 0.872340 (-2320 4830);
PAINT GREEN (-2320 4830);
DISPLAY INVISIBLE (-2320 4830);
FORCEPROP 1 LAST OFFPAGE TRUE
J 0
(-1950 4800);
DISPLAY 0.872340 (-1950 4800);
PAINT AQUA (-1950 4800);
DISPLAY INVISIBLE (-1950 4800);
FORCEPROP 2 LAST CDS_LIB standard
J 0
(-2275 4925);
DISPLAY INVISIBLE (-2275 4925);
FORCEADD Q_RES..1
(-8250 2950);
FORCEPROP 1 LAST LOCATION PR2522
J 0
(-8475 3000);
DISPLAY 0.723404 (-8475 3000);
PAINT AQUA (-8475 3000);
FORCEPROP 0 LAST $SEC 1
J 0
(-8150 3050);
DISPLAY 0.680851 (-8150 3050);
PAINT MONO (-8150 3050);
DISPLAY INVISIBLE (-8150 3050);
FORCEPROP 0 LAST CDS_SEC 1
J 0
(-8150 3050);
DISPLAY 1.021277 (-8150 3050);
DISPLAY INVISIBLE (-8150 3050);
FORCEPROP 1 LASTPIN (-8350 2950) $PN 1
J 0
(-8338 2962);
DISPLAY 0.787234 (-8338 2962);
PAINT MONO (-8338 2962);
FORCEPROP 1 LASTPIN (-8150 2950) $PN 2
J 0
(-8188 2962);
DISPLAY 0.787234 (-8188 2962);
PAINT MONO (-8188 2962);
FORCEPROP 1 LAST MATERIAL CHIP
J 0
(-8150 3000);
DISPLAY 0.723404 (-8150 3000);
PAINT SKYBLUE (-8150 3000);
FORCEPROP 1 LAST TOLERANCE 1%
J 0
(-8225 3000);
DISPLAY 0.723404 (-8225 3000);
PAINT SKYBLUE (-8225 3000);
FORCEPROP 1 LAST VALUE 1
J 2
(-8275 3000);
DISPLAY 0.723404 (-8275 3000);
PAINT SKYBLUE (-8275 3000);
FORCEPROP 0 LAST ROOM HSC BOM2
J 0
(-8850 2950);
DISPLAY 0.680851 (-8850 2950);
FORCEPROP 1 LAST PART_NUMBER CS-1002FB04
J 0
(-8225 2750);
DISPLAY 0.723404 (-8225 2750);
PAINT WHITE (-8225 2750);
DISPLAY INVISIBLE (-8225 2750);
FORCEPROP 1 LAST PATH I7
J 0
(-8300 3100);
DISPLAY 0.978723 (-8300 3100);
PAINT WHITE (-8300 3100);
DISPLAY INVISIBLE (-8300 3100);
FORCEPROP 2 LAST CDS_LIB pure_quanta
J 0
(-8250 2950);
DISPLAY INVISIBLE (-8250 2950);
FORCEPROP 1 LAST PACK_TYPE 0402LF
J 0
(-8325 2900);
DISPLAY 0.723404 (-8325 2900);
PAINT SKYBLUE (-8325 2900);
DISPLAY INVISIBLE (-8325 2900);
FORCEPROP 1 LAST WATTAGE 1/16W
J 2
(-7925 2900);
DISPLAY 0.723404 (-7925 2900);
PAINT SKYBLUE (-7925 2900);
DISPLAY INVISIBLE (-7925 2900);
FORCEADD Q_CAP..1
(-1175 1275);
FORCEPROP 1 LAST LOCATION PC1751
J 0
(-1125 1350);
DISPLAY 0.787234 (-1125 1350);
FORCEPROP 0 LAST $SEC 1
J 0
(-1125 1400);
DISPLAY 0.680851 (-1125 1400);
PAINT MONO (-1125 1400);
DISPLAY INVISIBLE (-1125 1400);
FORCEPROP 0 LAST CDS_SEC 1
J 0
(-1125 1400);
DISPLAY 1.021277 (-1125 1400);
DISPLAY INVISIBLE (-1125 1400);
FORCEPROP 1 LASTPIN (-1175 1375) $PN 1
J 0
(-1165 1355);
DISPLAY 0.787234 (-1165 1355);
PAINT MONO (-1165 1355);
FORCEPROP 1 LASTPIN (-1175 1175) $PN 2
J 0
(-1165 1155);
DISPLAY 0.787234 (-1165 1155);
PAINT MONO (-1165 1155);
FORCEPROP 0 LAST ROOM HSC BOM2
J 0
(-1100 1175);
DISPLAY 0.553191 (-1100 1175);
FORCEPROP 1 LAST PACK_TYPE 0402
J 0
(-1125 1200);
DISPLAY 0.574468 (-1125 1200);
PAINT SKYBLUE (-1125 1200);
FORCEPROP 1 LAST VOLTAGE 50V
J 0
(-1125 1300);
DISPLAY 0.574468 (-1125 1300);
PAINT SKYBLUE (-1125 1300);
FORCEPROP 1 LAST TOLERANCE 10%
J 0
(-1125 1275);
DISPLAY 0.574468 (-1125 1275);
PAINT SKYBLUE (-1125 1275);
FORCEPROP 1 LAST MATERIAL EMPTY
J 0
(-1125 1250);
DISPLAY 0.574468 (-1125 1250);
PAINT RED (-1125 1250);
FORCEPROP 1 LAST VALUE 1NF
J 0
(-1125 1325);
DISPLAY 0.574468 (-1125 1325);
PAINT SKYBLUE (-1125 1325);
FORCEPROP 1 LAST PART_NUMBER CH21006KB16
J 0
(-1125 1225);
DISPLAY 0.574468 (-1125 1225);
PAINT WHITE (-1125 1225);
DISPLAY INVISIBLE (-1125 1225);
FORCEPROP 1 LAST PATH I70
J 0
(-1125 1425);
DISPLAY 0.978723 (-1125 1425);
PAINT WHITE (-1125 1425);
DISPLAY INVISIBLE (-1125 1425);
FORCEPROP 2 LAST CDS_LIB pure_quanta
J 0
(-1175 1275);
DISPLAY INVISIBLE (-1175 1275);
FORCEADD Q_RES..2
(-1175 1600);
FORCEPROP 1 LAST LOCATION PR2537
J 0
(-1125 1675);
DISPLAY 0.787234 (-1125 1675);
FORCEPROP 0 LAST $SEC 1
J 0
(-1125 1725);
DISPLAY 0.680851 (-1125 1725);
PAINT MONO (-1125 1725);
DISPLAY INVISIBLE (-1125 1725);
FORCEPROP 0 LAST CDS_SEC 1
J 0
(-1125 1725);
DISPLAY 1.021277 (-1125 1725);
DISPLAY INVISIBLE (-1125 1725);
FORCEPROP 1 LASTPIN (-1175 1700) $PN 1
J 0
(-1170 1662);
DISPLAY 0.787234 (-1170 1662);
PAINT MONO (-1170 1662);
FORCEPROP 1 LASTPIN (-1175 1500) $PN 2
J 0
(-1170 1510);
DISPLAY 0.787234 (-1170 1510);
PAINT MONO (-1170 1510);
FORCEPROP 1 LAST PACK_TYPE 0402LF
J 0
(-1125 1525);
DISPLAY 0.574468 (-1125 1525);
PAINT SKYBLUE (-1125 1525);
FORCEPROP 0 LAST ROOM HSC BOM2
J 0
(-1125 1725);
DISPLAY 0.680851 (-1125 1725);
FORCEPROP 1 LAST WATTAGE 1/16W
J 0
(-1125 1600);
DISPLAY 0.574468 (-1125 1600);
PAINT SKYBLUE (-1125 1600);
FORCEPROP 1 LAST TOLERANCE 1%
J 0
(-1125 1625);
DISPLAY 0.574468 (-1125 1625);
PAINT SKYBLUE (-1125 1625);
FORCEPROP 1 LAST VALUE 10
J 0
(-1125 1650);
DISPLAY 0.574468 (-1125 1650);
PAINT SKYBLUE (-1125 1650);
FORCEPROP 1 LAST MATERIAL EMPTY
J 0
(-1125 1575);
DISPLAY 0.574468 (-1125 1575);
PAINT RED (-1125 1575);
FORCEPROP 1 LAST PART_NUMBER CS01002FB07
J 0
(-1125 1550);
DISPLAY 0.574468 (-1125 1550);
PAINT WHITE (-1125 1550);
DISPLAY INVISIBLE (-1125 1550);
FORCEPROP 1 LAST PATH I71
J 0
(-1125 1775);
DISPLAY 0.978723 (-1125 1775);
PAINT WHITE (-1125 1775);
DISPLAY INVISIBLE (-1125 1775);
FORCEPROP 2 LAST CDS_LIB pure_quanta
J 0
(-1175 1600);
DISPLAY INVISIBLE (-1175 1600);
FORCEADD SS15P3SM386A..1
R 1
(-475 1375);
FORCEPROP 1 LAST LOCATION PD17
J 2
(-575 1125);
DISPLAY 0.723404 (-575 1125);
PAINT AQUA (-575 1125);
FORCEPROP 0 LAST $SEC 1
R 1
J 0
(-375 1475);
DISPLAY 0.680851 (-375 1475);
PAINT MONO (-375 1475);
DISPLAY INVISIBLE (-375 1475);
FORCEPROP 0 LAST CDS_SEC 1
R 1
J 0
(-375 1475);
DISPLAY 1.021277 (-375 1475);
DISPLAY INVISIBLE (-375 1475);
FORCEPROP 0 LASTPIN (-525 1100) $PN 1
R 1
J 2
(-535 1090);
DISPLAY 0.680851 (-535 1090);
PAINT MONO (-535 1090);
FORCEPROP 0 LASTPIN (-425 1100) $PN 2
R 1
J 2
(-435 1090);
DISPLAY 0.680851 (-435 1090);
PAINT MONO (-435 1090);
FORCEPROP 0 LASTPIN (-475 1650) $PN K
R 1
J 0
(-485 1660);
DISPLAY 0.680851 (-485 1660);
PAINT MONO (-485 1660);
FORCEPROP 2 LAST VALUE SS15P3S-M3/86A
J 2
(-575 1025);
DISPLAY 0.808511 (-575 1025);
PAINT SKYBLUE (-575 1025);
FORCEPROP 1 LAST MATERIAL IC
J 2
(-575 875);
DISPLAY 0.723404 (-575 875);
PAINT SKYBLUE (-575 875);
FORCEPROP 0 LAST ROOM HSC BOM2
J 0
(-800 800);
DISPLAY 0.680851 (-800 800);
FORCEPROP 2 LAST PART_TYPE SMLF
J 2
(-575 1075);
DISPLAY 1.021277 (-575 1075);
FORCEPROP 1 LAST PART_NUMBER BC015P3SZ00
J 2
(-575 950);
DISPLAY 0.723404 (-575 950);
PAINT WHITE (-575 950);
DISPLAY INVISIBLE (-575 950);
FORCEPROP 1 LAST PATH I72
R 1
J 0
(-475 1375);
DISPLAY 0.723404 (-475 1375);
PAINT GREEN (-475 1375);
DISPLAY INVISIBLE (-475 1375);
FORCEPROP 2 LAST CDS_LIB pure_quanta
J 0
(-475 1375);
DISPLAY INVISIBLE (-475 1375);
FORCEPROP 1 LAST CDS_LMAN_SYM_OUTLINE -125,100,125,-100
R 1
J 0
(-475 1375);
DISPLAY 0.468085 (-475 1375);
PAINT GREEN (-475 1375);
DISPLAY INVISIBLE (-475 1375);
FORCEPROP 1 LAST NEEDS_NO_SIZE TRUE
R 1
J 0
(-475 1375);
DISPLAY 0.723404 (-475 1375);
PAINT GREEN (-475 1375);
DISPLAY INVISIBLE (-475 1375);
FORCEADD UNIVERSAL_POWER..1
(-850 2175);
FORCEPROP 3 LASTPIN (-850 2125) SIG_NAME P12V_AUX\g
J 0
(-840 2135);
DISPLAY 0.659574 (-840 2135);
PAINT MONO (-840 2135);
DISPLAY INVISIBLE (-840 2135);
FORCEPROP 1 LAST HDL_POWER P12V_AUX
J 1
(-850 2225);
DISPLAY 0.723404 (-850 2225);
PAINT GREEN (-850 2225);
FORCEPROP 1 LAST PATH I73
J 0
(-800 2200);
DISPLAY 0.872340 (-800 2200);
PAINT AQUA (-800 2200);
DISPLAY INVISIBLE (-800 2200);
FORCEPROP 2 LAST BOM_COST MIO_VRD_SB
J 0
(-850 2275);
DISPLAY 0.617021 (-850 2275);
PAINT PURPLE (-850 2275);
DISPLAY INVISIBLE (-850 2275);
FORCEPROP 2 LAST ROOM AUX_SW
J 0
(-850 2275);
DISPLAY 0.617021 (-850 2275);
DISPLAY INVISIBLE (-850 2275);
FORCEPROP 2 LAST CDS_LIB pure_quanta_power
J 0
(-850 2175);
DISPLAY INVISIBLE (-850 2175);
FORCEADD Q_RES..2
(-875 3025);
FORCEPROP 1 LAST LOCATION PR2538
J 0
(-830 3150);
DISPLAY 0.978723 (-830 3150);
FORCEPROP 0 LAST $SEC 1
J 0
(-825 3200);
DISPLAY 0.680851 (-825 3200);
PAINT MONO (-825 3200);
DISPLAY INVISIBLE (-825 3200);
FORCEPROP 0 LAST CDS_SEC 1
J 0
(-825 3200);
DISPLAY 1.021277 (-825 3200);
DISPLAY INVISIBLE (-825 3200);
FORCEPROP 1 LASTPIN (-875 3125) $PN 1
J 0
(-870 3087);
DISPLAY 0.787234 (-870 3087);
PAINT MONO (-870 3087);
FORCEPROP 1 LASTPIN (-875 2925) $PN 2
J 0
(-870 2935);
DISPLAY 0.787234 (-870 2935);
PAINT MONO (-870 2935);
FORCEPROP 1 LAST PACK_TYPE 0402LF
J 0
(-835 2850);
DISPLAY 0.723404 (-835 2850);
PAINT SKYBLUE (-835 2850);
FORCEPROP 1 LAST MATERIAL CHIP
J 0
(-835 2950);
DISPLAY 0.723404 (-835 2950);
PAINT SKYBLUE (-835 2950);
FORCEPROP 1 LAST WATTAGE 1/16W
J 0
(-835 3000);
DISPLAY 0.723404 (-835 3000);
PAINT SKYBLUE (-835 3000);
FORCEPROP 1 LAST TOLERANCE 1%
J 0
(-830 3050);
DISPLAY 0.723404 (-830 3050);
PAINT SKYBLUE (-830 3050);
FORCEPROP 1 LAST VALUE 10
J 0
(-830 3100);
DISPLAY 0.723404 (-830 3100);
PAINT SKYBLUE (-830 3100);
FORCEPROP 0 LAST ROOM HSC BOM2
J 0
(-825 3225);
DISPLAY 0.680851 (-825 3225);
FORCEPROP 1 LAST PART_NUMBER CS01002FB07
J 0
(-835 2900);
DISPLAY 0.723404 (-835 2900);
PAINT WHITE (-835 2900);
DISPLAY INVISIBLE (-835 2900);
FORCEPROP 1 LAST PATH I74
J 0
(-825 3200);
DISPLAY 0.978723 (-825 3200);
PAINT WHITE (-825 3200);
DISPLAY INVISIBLE (-825 3200);
FORCEPROP 2 LAST CDS_LIB pure_quanta
J 0
(-875 3025);
DISPLAY INVISIBLE (-875 3025);
FORCEADD MOSFET_NCH_1D3S..1
R 6
(-375 3525);
FORCEPROP 1 LAST LOCATION PPQ9
J 0
(-825 3925);
DISPLAY 0.723404 (-825 3925);
PAINT GREEN (-825 3925);
FORCEPROP 0 LAST $SEC 1
J 0
(-825 4075);
DISPLAY 0.680851 (-825 4075);
PAINT MONO (-825 4075);
DISPLAY INVISIBLE (-825 4075);
FORCEPROP 0 LAST CDS_SEC 1
J 0
(-825 4075);
DISPLAY 1.021277 (-825 4075);
DISPLAY INVISIBLE (-825 4075);
FORCEPROP 0 LASTPIN (-275 3275) $PN 1
R 1
J 2
(-285 3265);
DISPLAY 0.680851 (-285 3265);
PAINT MONO (-285 3265);
FORCEPROP 0 LASTPIN (-375 3275) $PN 2
R 1
J 2
(-385 3265);
DISPLAY 0.680851 (-385 3265);
PAINT MONO (-385 3265);
FORCEPROP 0 LASTPIN (-475 3275) $PN 3
R 1
J 2
(-485 3265);
DISPLAY 0.680851 (-485 3265);
PAINT MONO (-485 3265);
FORCEPROP 0 LASTPIN (-575 3475) $PN 4
J 2
(-585 3485);
DISPLAY 0.680851 (-585 3485);
PAINT MONO (-585 3485);
FORCEPROP 0 LASTPIN (-375 3775) $PN 5
R 1
J 0
(-385 3785);
DISPLAY 0.680851 (-385 3785);
PAINT MONO (-385 3785);
FORCEPROP 0 LAST ROOM HSC BOM2
J 0
(-825 3775);
DISPLAY 0.680851 (-825 3775);
FORCEPROP 2 LAST VALUE PSMNR58-30YLH
J 0
(-825 3877);
DISPLAY 0.723404 (-825 3877);
PAINT SKYBLUE (-825 3877);
FORCEPROP 2 LAST PART_TYPE SMLF
J 0
(-825 3827);
DISPLAY 1.021277 (-825 3827);
FORCEPROP 1 LAST MATERIAL IC
J 0
(-825 4025);
DISPLAY 0.723404 (-825 4025);
PAINT SKYBLUE (-825 4025);
FORCEPROP 1 LAST PART_NUMBER BAMNR580000
J 0
(-825 3966);
DISPLAY 0.723404 (-825 3966);
PAINT WHITE (-825 3966);
DISPLAY INVISIBLE (-825 3966);
FORCEPROP 1 LAST PATH I75
J 0
(-375 3525);
DISPLAY 0.723404 (-375 3525);
PAINT GREEN (-375 3525);
DISPLAY INVISIBLE (-375 3525);
FORCEPROP 1 LAST NEEDS_NO_SIZE TRUE
J 0
(-375 3504);
DISPLAY 0.468085 (-375 3504);
PAINT GREEN (-375 3504);
DISPLAY INVISIBLE (-375 3504);
FORCEPROP 2 LAST CDS_LIB pure_quanta
J 0
(-375 3525);
DISPLAY INVISIBLE (-375 3525);
FORCEPROP 1 LAST CDS_LMAN_SYM_OUTLINE -150,200,150,-200
J 0
(-375 3525);
DISPLAY 0.468085 (-375 3525);
PAINT GREEN (-375 3525);
DISPLAY INVISIBLE (-375 3525);
FORCEADD OFFPAGE..2
(-2275 5275);
FORCEPROP 2 LAST $XR0 267 
J 0
(-2086 5275);
DISPLAY 0.638298 (-2086 5275);
PAINT MONO (-2086 5275);
FORCEPROP 2 LAST $XR1 268 
J 0
(-1966 5275);
DISPLAY 0.638298 (-1966 5275);
PAINT MONO (-1966 5275);
FORCEPROP 2 LAST PATH I76
J 0
(-2100 5350);
DISPLAY 0.680851 (-2100 5350);
DISPLAY INVISIBLE (-2100 5350);
FORCEPROP 1 LAST COMMENT_BODY TRUE
J 0
(-2320 5180);
DISPLAY 0.872340 (-2320 5180);
PAINT GREEN (-2320 5180);
DISPLAY INVISIBLE (-2320 5180);
FORCEPROP 1 LAST OFFPAGE TRUE
J 0
(-1950 5150);
DISPLAY 0.872340 (-1950 5150);
PAINT AQUA (-1950 5150);
DISPLAY INVISIBLE (-1950 5150);
FORCEPROP 2 LAST CDS_LIB standard
J 0
(-2275 5275);
DISPLAY INVISIBLE (-2275 5275);
FORCEADD UNIVERSAL_POWER..1
(-1750 5050);
FORCEPROP 3 LASTPIN (-1750 5000) SIG_NAME P12V_MAIN_R\g
J 0
(-1740 5010);
DISPLAY 0.659574 (-1740 5010);
PAINT MONO (-1740 5010);
DISPLAY INVISIBLE (-1740 5010);
FORCEPROP 1 LAST HDL_POWER P12V_MAIN_R
J 1
(-1750 5100);
DISPLAY 0.723404 (-1750 5100);
PAINT GREEN (-1750 5100);
FORCEPROP 1 LAST PATH I77
J 0
(-1700 5075);
DISPLAY 0.872340 (-1700 5075);
PAINT AQUA (-1700 5075);
DISPLAY INVISIBLE (-1700 5075);
FORCEPROP 2 LAST CDS_LIB pure_quanta_power
J 0
(-1750 5050);
DISPLAY INVISIBLE (-1750 5050);
FORCEPROP 2 LAST ROOM AUX_SW
J 0
(-1750 5150);
DISPLAY 0.617021 (-1750 5150);
DISPLAY INVISIBLE (-1750 5150);
FORCEPROP 2 LAST BOM_COST MIO_VRD_SB
J 0
(-1750 5150);
DISPLAY 0.617021 (-1750 5150);
PAINT PURPLE (-1750 5150);
DISPLAY INVISIBLE (-1750 5150);
FORCEADD UNIVERSAL_POWER..1
(-1350 5300);
FORCEPROP 3 LASTPIN (-1350 5250) SIG_NAME P12V_MAIN_R_0\g
J 0
(-1340 5260);
DISPLAY 0.659574 (-1340 5260);
PAINT MONO (-1340 5260);
DISPLAY INVISIBLE (-1340 5260);
FORCEPROP 1 LAST HDL_POWER P12V_MAIN_R_0
J 1
(-1350 5350);
DISPLAY 0.723404 (-1350 5350);
PAINT GREEN (-1350 5350);
FORCEPROP 1 LAST PATH I78
J 0
(-1300 5325);
DISPLAY 0.872340 (-1300 5325);
PAINT AQUA (-1300 5325);
DISPLAY INVISIBLE (-1300 5325);
FORCEPROP 2 LAST ROOM AUX_SW
J 0
(-1350 5400);
DISPLAY 0.617021 (-1350 5400);
DISPLAY INVISIBLE (-1350 5400);
FORCEPROP 2 LAST BOM_COST MIO_VRD_SB
J 0
(-1350 5400);
DISPLAY 0.617021 (-1350 5400);
PAINT PURPLE (-1350 5400);
DISPLAY INVISIBLE (-1350 5400);
FORCEPROP 2 LAST CDS_LIB pure_quanta_power
J 0
(-1350 5300);
DISPLAY INVISIBLE (-1350 5300);
FORCEADD MOSFET_NCH_1D3S..1
R 6
(-3575 2325);
FORCEPROP 1 LAST LOCATION PPQ8
J 0
(-3423 2359);
DISPLAY 0.723404 (-3423 2359);
PAINT AQUA (-3423 2359);
FORCEPROP 0 LAST $SEC 1
J 0
(-3400 2525);
DISPLAY INVISIBLE (-3400 2525);
FORCEPROP 0 LAST CDS_SEC 1
J 0
(-3400 2525);
DISPLAY INVISIBLE (-3400 2525);
FORCEPROP 0 LASTPIN (-3475 2075) $PN 1
R 1
J 2
(-3485 2065);
DISPLAY 0.808511 (-3485 2065);
FORCEPROP 0 LASTPIN (-3575 2075) $PN 2
R 1
J 2
(-3585 2065);
DISPLAY 0.808511 (-3585 2065);
FORCEPROP 0 LASTPIN (-3675 2075) $PN 3
R 1
J 2
(-3685 2065);
DISPLAY 0.808511 (-3685 2065);
FORCEPROP 0 LASTPIN (-3775 2275) $PN 4
J 2
(-3785 2285);
DISPLAY 0.808511 (-3785 2285);
FORCEPROP 0 LASTPIN (-3575 2575) $PN 5
R 1
J 0
(-3585 2585);
DISPLAY 0.808511 (-3585 2585);
FORCEPROP 1 LAST MATERIAL IC
J 0
(-3423 2475);
DISPLAY 0.723404 (-3423 2475);
PAINT SKYBLUE (-3423 2475);
FORCEPROP 0 LAST ROOM HSC BOM2
J 0
(-3400 2525);
DISPLAY 0.680851 (-3400 2525);
FORCEPROP 2 LAST PART_TYPE SMLF
J 0
(-3400 2252);
DISPLAY 1.021277 (-3400 2252);
FORCEPROP 2 LAST VALUE PSMNR58-30YLH
J 0
(-3400 2302);
DISPLAY 0.723404 (-3400 2302);
PAINT SKYBLUE (-3400 2302);
FORCEPROP 1 LAST PART_NUMBER BAMNR580000
J 0
(-3423 2416);
DISPLAY 0.723404 (-3423 2416);
PAINT WHITE (-3423 2416);
DISPLAY INVISIBLE (-3423 2416);
FORCEPROP 1 LAST PATH I79
J 0
(-3575 2325);
DISPLAY 0.723404 (-3575 2325);
PAINT GREEN (-3575 2325);
DISPLAY INVISIBLE (-3575 2325);
FORCEPROP 2 LAST CDS_LIB pure_quanta
J 0
(-3575 2278);
DISPLAY INVISIBLE (-3575 2278);
FORCEPROP 1 LAST NEEDS_NO_SIZE TRUE
J 0
(-3575 2304);
DISPLAY 0.468085 (-3575 2304);
PAINT GREEN (-3575 2304);
DISPLAY INVISIBLE (-3575 2304);
FORCEPROP 1 LAST CDS_LMAN_SYM_OUTLINE -150,200,150,-200
J 0
(-3575 2303);
DISPLAY 0.468085 (-3575 2303);
PAINT GREEN (-3575 2303);
DISPLAY INVISIBLE (-3575 2303);
FORCEADD Q_RES..1
(-8250 3150);
FORCEPROP 1 LAST LOCATION PR2520
J 0
(-8475 3200);
DISPLAY 0.723404 (-8475 3200);
PAINT AQUA (-8475 3200);
FORCEPROP 0 LAST $SEC 1
J 0
(-7775 3200);
DISPLAY INVISIBLE (-7775 3200);
FORCEPROP 0 LAST CDS_SEC 1
J 0
(-7775 3200);
DISPLAY INVISIBLE (-7775 3200);
FORCEPROP 1 LASTPIN (-8350 3150) $PN 1
J 0
(-8338 3162);
DISPLAY 0.723404 (-8338 3162);
PAINT MONO (-8338 3162);
FORCEPROP 1 LASTPIN (-8150 3150) $PN 2
J 0
(-8188 3162);
DISPLAY 0.723404 (-8188 3162);
PAINT MONO (-8188 3162);
FORCEPROP 1 LAST TOLERANCE 1%
J 0
(-8225 3200);
DISPLAY 0.723404 (-8225 3200);
PAINT SKYBLUE (-8225 3200);
FORCEPROP 1 LAST VALUE 1
J 2
(-8275 3200);
DISPLAY 0.723404 (-8275 3200);
PAINT SKYBLUE (-8275 3200);
FORCEPROP 0 LAST ROOM HSC BOM2
J 0
(-8850 3150);
DISPLAY 0.680851 (-8850 3150);
FORCEPROP 1 LAST MATERIAL CHIP
J 0
(-8150 3200);
DISPLAY 0.723404 (-8150 3200);
PAINT SKYBLUE (-8150 3200);
FORCEPROP 1 LAST PART_NUMBER CS-1002FB04
J 0
(-8225 2950);
DISPLAY 0.723404 (-8225 2950);
PAINT WHITE (-8225 2950);
DISPLAY INVISIBLE (-8225 2950);
FORCEPROP 1 LAST PATH I8
J 0
(-8300 3300);
DISPLAY 0.978723 (-8300 3300);
PAINT WHITE (-8300 3300);
DISPLAY INVISIBLE (-8300 3300);
FORCEPROP 1 LAST WATTAGE 1/16W
J 2
(-7925 3100);
DISPLAY 0.723404 (-7925 3100);
PAINT SKYBLUE (-7925 3100);
DISPLAY INVISIBLE (-7925 3100);
FORCEPROP 1 LAST PACK_TYPE 0402LF
J 0
(-8325 3100);
DISPLAY 0.723404 (-8325 3100);
PAINT SKYBLUE (-8325 3100);
DISPLAY INVISIBLE (-8325 3100);
FORCEPROP 2 LAST CDS_LIB pure_quanta
J 0
(-8250 3150);
DISPLAY INVISIBLE (-8250 3150);
FORCEADD MOSFET_NCH_1D3S..1
R 6
(-4450 2325);
FORCEPROP 1 LAST LOCATION PPQ7
J 0
(-4298 2359);
DISPLAY 0.723404 (-4298 2359);
PAINT AQUA (-4298 2359);
FORCEPROP 0 LAST $SEC 1
J 0
(-4275 2525);
DISPLAY INVISIBLE (-4275 2525);
FORCEPROP 0 LAST CDS_SEC 1
J 0
(-4275 2525);
DISPLAY INVISIBLE (-4275 2525);
FORCEPROP 0 LASTPIN (-4350 2075) $PN 1
R 1
J 2
(-4360 2065);
DISPLAY 0.808511 (-4360 2065);
FORCEPROP 0 LASTPIN (-4450 2075) $PN 2
R 1
J 2
(-4460 2065);
DISPLAY 0.808511 (-4460 2065);
FORCEPROP 0 LASTPIN (-4550 2075) $PN 3
R 1
J 2
(-4560 2065);
DISPLAY 0.808511 (-4560 2065);
FORCEPROP 0 LASTPIN (-4650 2275) $PN 4
J 2
(-4660 2285);
DISPLAY 0.808511 (-4660 2285);
FORCEPROP 0 LASTPIN (-4450 2575) $PN 5
R 1
J 0
(-4460 2585);
DISPLAY 0.808511 (-4460 2585);
FORCEPROP 0 LAST ROOM HSC BOM2
J 0
(-4275 2525);
DISPLAY 0.680851 (-4275 2525);
FORCEPROP 2 LAST VALUE PSMNR58-30YLH
J 0
(-4275 2302);
DISPLAY 0.723404 (-4275 2302);
PAINT SKYBLUE (-4275 2302);
FORCEPROP 2 LAST PART_TYPE SMLF
J 0
(-4275 2252);
DISPLAY 1.021277 (-4275 2252);
FORCEPROP 1 LAST MATERIAL IC
J 0
(-4298 2475);
DISPLAY 0.723404 (-4298 2475);
PAINT SKYBLUE (-4298 2475);
FORCEPROP 1 LAST PART_NUMBER BAMNR580000
J 0
(-4298 2416);
DISPLAY 0.723404 (-4298 2416);
PAINT WHITE (-4298 2416);
DISPLAY INVISIBLE (-4298 2416);
FORCEPROP 1 LAST PATH I80
J 0
(-4450 2325);
DISPLAY 0.723404 (-4450 2325);
PAINT GREEN (-4450 2325);
DISPLAY INVISIBLE (-4450 2325);
FORCEPROP 1 LAST CDS_LMAN_SYM_OUTLINE -150,200,150,-200
J 0
(-4450 2303);
DISPLAY 0.468085 (-4450 2303);
PAINT GREEN (-4450 2303);
DISPLAY INVISIBLE (-4450 2303);
FORCEPROP 1 LAST NEEDS_NO_SIZE TRUE
J 0
(-4450 2304);
DISPLAY 0.468085 (-4450 2304);
PAINT GREEN (-4450 2304);
DISPLAY INVISIBLE (-4450 2304);
FORCEPROP 2 LAST CDS_LIB pure_quanta
J 0
(-4450 2278);
DISPLAY INVISIBLE (-4450 2278);
FORCEADD Q_SP_RES4P..1
R 6
(-3500 5250);
FORCEPROP 1 LAST LOCATION PR6002
J 0
(-3650 5525);
DISPLAY 0.723404 (-3650 5525);
PAINT GREEN (-3650 5525);
FORCEPROP 2 LAST SEC 1
J 0
(-3500 5250);
DISPLAY 0.680851 (-3500 5250);
PAINT MONO (-3500 5250);
DISPLAY INVISIBLE (-3500 5250);
FORCEPROP 2 LASTPIN (-3700 5225) $PN 1A
J 2
(-3710 5235);
DISPLAY 0.680851 (-3710 5235);
PAINT MONO (-3710 5235);
FORCEPROP 2 LASTPIN (-3700 5275) $PN 1B
J 2
(-3710 5285);
DISPLAY 0.680851 (-3710 5285);
PAINT MONO (-3710 5285);
FORCEPROP 2 LASTPIN (-3300 5225) $PN 2A
J 0
(-3290 5235);
DISPLAY 0.680851 (-3290 5235);
PAINT MONO (-3290 5235);
FORCEPROP 2 LASTPIN (-3300 5275) $PN 2B
J 0
(-3290 5285);
DISPLAY 0.680851 (-3290 5285);
PAINT MONO (-3290 5285);
FORCEPROP 0 LAST ROOM HSC BOM2
J 0
(-3650 5700);
DISPLAY 0.680851 (-3650 5700);
FORCEPROP 2 LAST PART_TYPE SMLF
J 0
(-3650 5322);
DISPLAY 0.680851 (-3650 5322);
FORCEPROP 2 LAST TOLERANCE 1%
J 0
(-3650 5422);
DISPLAY 0.680851 (-3650 5422);
FORCEPROP 1 LAST MATERIAL CHIP
J 0
(-3650 5643);
DISPLAY 0.723404 (-3650 5643);
PAINT GREEN (-3650 5643);
FORCEPROP 2 LAST VALUE 0.003
J 0
(-3650 5472);
DISPLAY 0.680851 (-3650 5472);
FORCEPROP 2 LAST WATTAGE 2W
J 0
(-3650 5372);
DISPLAY 0.680851 (-3650 5372);
FORCEPROP 1 LAST PART_NUMBER SP_CS+003AFR00_1
J 0
(-3650 5583);
DISPLAY 0.723404 (-3650 5583);
PAINT GREEN (-3650 5583);
DISPLAY INVISIBLE (-3650 5583);
FORCEPROP 1 LAST PATH I81
J 0
(-3500 5216);
DISPLAY 0.723404 (-3500 5216);
PAINT GREEN (-3500 5216);
DISPLAY INVISIBLE (-3500 5216);
FORCEPROP 2 LAST CDS_LIB pure_quanta
J 0
(-3500 5203);
DISPLAY INVISIBLE (-3500 5203);
FORCEPROP 1 LAST NEEDS_NO_SIZE TRUE
J 0
(-3350 5222);
DISPLAY 0.468085 (-3350 5222);
PAINT GREEN (-3350 5222);
DISPLAY INVISIBLE (-3350 5222);
FORCEPROP 1 LAST CDS_LMAN_SYM_OUTLINE -150,75,150,-75
J 0
(-3500 5228);
DISPLAY 0.468085 (-3500 5228);
PAINT GREEN (-3500 5228);
DISPLAY INVISIBLE (-3500 5228);
FORCEPROP 2 LAST SEC_TYPE 
J 0
(-3500 5250);
DISPLAY 0.680851 (-3500 5250);
DISPLAY INVISIBLE (-3500 5250);
FORCEADD Q_RES..1
(-8275 4275);
FORCEPROP 1 LAST LOCATION PR2514
J 0
(-8500 4275);
DISPLAY 0.638298 (-8500 4275);
FORCEPROP 0 LAST $SEC 1
J 0
(-8300 4375);
DISPLAY 0.680851 (-8300 4375);
PAINT MONO (-8300 4375);
DISPLAY INVISIBLE (-8300 4375);
FORCEPROP 0 LAST CDS_SEC 1
J 0
(-8300 4375);
DISPLAY 0.680851 (-8300 4375);
DISPLAY INVISIBLE (-8300 4375);
FORCEPROP 1 LASTPIN (-8375 4275) $PN 1
J 0
(-8363 4287);
DISPLAY 0.787234 (-8363 4287);
PAINT MONO (-8363 4287);
FORCEPROP 1 LASTPIN (-8175 4275) $PN 2
J 0
(-8213 4287);
DISPLAY 0.787234 (-8213 4287);
PAINT MONO (-8213 4287);
FORCEPROP 1 LAST MATERIAL CHIP
J 0
(-8325 4225);
DISPLAY 0.638298 (-8325 4225);
FORCEPROP 1 LAST VALUE 10
J 2
(-8300 4325);
DISPLAY 0.638298 (-8300 4325);
FORCEPROP 1 LAST TOLERANCE 1%
J 0
(-8225 4300);
DISPLAY 0.638298 (-8225 4300);
FORCEPROP 1 LAST PACK_TYPE 0402LF
J 0
(-8175 4225);
DISPLAY 0.638298 (-8175 4225);
FORCEPROP 0 LAST ROOM HSC BOM2
J 0
(-8825 4275);
DISPLAY 0.680851 (-8825 4275);
FORCEPROP 1 LAST WATTAGE 1/16W
J 2
(-8350 4225);
DISPLAY 0.638298 (-8350 4225);
FORCEPROP 1 LAST PART_NUMBER CS01002FB07
J 0
(-8325 4375);
DISPLAY 0.978723 (-8325 4375);
DISPLAY INVISIBLE (-8325 4375);
FORCEPROP 1 LAST PATH I82
J 0
(-8325 4425);
DISPLAY 0.978723 (-8325 4425);
PAINT WHITE (-8325 4425);
DISPLAY INVISIBLE (-8325 4425);
FORCEPROP 2 LAST CDS_LIB pure_quanta
J 0
(-8275 4275);
DISPLAY INVISIBLE (-8275 4275);
FORCEADD Q_RES..1
(-8250 3925);
FORCEPROP 1 LAST LOCATION PR2515
J 0
(-8475 3925);
DISPLAY 0.638298 (-8475 3925);
FORCEPROP 0 LAST $SEC 1
J 0
(-8150 4025);
DISPLAY 0.680851 (-8150 4025);
PAINT MONO (-8150 4025);
DISPLAY INVISIBLE (-8150 4025);
FORCEPROP 0 LAST CDS_SEC 1
J 0
(-8150 4025);
DISPLAY 0.680851 (-8150 4025);
DISPLAY INVISIBLE (-8150 4025);
FORCEPROP 1 LASTPIN (-8350 3925) $PN 1
J 0
(-8338 3937);
DISPLAY 0.787234 (-8338 3937);
PAINT MONO (-8338 3937);
FORCEPROP 1 LASTPIN (-8150 3925) $PN 2
J 0
(-8188 3937);
DISPLAY 0.787234 (-8188 3937);
PAINT MONO (-8188 3937);
FORCEPROP 1 LAST VALUE 10
J 2
(-8300 3975);
DISPLAY 0.638298 (-8300 3975);
FORCEPROP 1 LAST TOLERANCE 1%
J 0
(-8225 3975);
DISPLAY 0.638298 (-8225 3975);
FORCEPROP 1 LAST MATERIAL CHIP
J 0
(-8150 3975);
DISPLAY 0.638298 (-8150 3975);
FORCEPROP 0 LAST ROOM HSC BOM2
J 0
(-8825 3925);
DISPLAY 0.680851 (-8825 3925);
FORCEPROP 1 LAST PART_NUMBER CS01002FB07
J 0
(-8300 4025);
DISPLAY 0.978723 (-8300 4025);
DISPLAY INVISIBLE (-8300 4025);
FORCEPROP 1 LAST PATH I83
J 0
(-8300 4075);
DISPLAY 0.978723 (-8300 4075);
PAINT WHITE (-8300 4075);
DISPLAY INVISIBLE (-8300 4075);
FORCEPROP 1 LAST WATTAGE 1/16W
J 2
(-8325 3875);
DISPLAY 0.638298 (-8325 3875);
DISPLAY INVISIBLE (-8325 3875);
FORCEPROP 1 LAST PACK_TYPE 0402LF
J 0
(-8150 3875);
DISPLAY 0.638298 (-8150 3875);
DISPLAY INVISIBLE (-8150 3875);
FORCEPROP 2 LAST CDS_LIB pure_quanta
J 0
(-8250 3925);
DISPLAY INVISIBLE (-8250 3925);
FORCEADD Q_RES..1
(-8250 3825);
FORCEPROP 1 LAST LOCATION PR2516
J 0
(-8475 3825);
DISPLAY 0.638298 (-8475 3825);
FORCEPROP 0 LAST $SEC 1
J 0
(-8150 3925);
DISPLAY 0.680851 (-8150 3925);
PAINT MONO (-8150 3925);
DISPLAY INVISIBLE (-8150 3925);
FORCEPROP 0 LAST CDS_SEC 1
J 0
(-8150 3925);
DISPLAY 0.680851 (-8150 3925);
DISPLAY INVISIBLE (-8150 3925);
FORCEPROP 1 LASTPIN (-8350 3825) $PN 1
J 0
(-8338 3837);
DISPLAY 0.787234 (-8338 3837);
PAINT MONO (-8338 3837);
FORCEPROP 1 LASTPIN (-8150 3825) $PN 2
J 0
(-8188 3837);
DISPLAY 0.787234 (-8188 3837);
PAINT MONO (-8188 3837);
FORCEPROP 1 LAST VALUE 10
J 2
(-8275 3875);
DISPLAY 0.638298 (-8275 3875);
FORCEPROP 1 LAST MATERIAL CHIP
J 0
(-8150 3875);
DISPLAY 0.638298 (-8150 3875);
FORCEPROP 1 LAST TOLERANCE 1%
J 0
(-8225 3875);
DISPLAY 0.638298 (-8225 3875);
FORCEPROP 0 LAST ROOM HSC BOM2
J 0
(-8825 3825);
DISPLAY 0.680851 (-8825 3825);
FORCEPROP 1 LAST PART_NUMBER CS01002FB07
J 0
(-8300 3925);
DISPLAY 0.978723 (-8300 3925);
DISPLAY INVISIBLE (-8300 3925);
FORCEPROP 1 LAST PATH I84
J 0
(-8300 3975);
DISPLAY 0.978723 (-8300 3975);
PAINT WHITE (-8300 3975);
DISPLAY INVISIBLE (-8300 3975);
FORCEPROP 1 LAST WATTAGE 1/16W
J 2
(-8325 3775);
DISPLAY 0.638298 (-8325 3775);
DISPLAY INVISIBLE (-8325 3775);
FORCEPROP 1 LAST PACK_TYPE 0402LF
J 0
(-8150 3775);
DISPLAY 0.638298 (-8150 3775);
DISPLAY INVISIBLE (-8150 3775);
FORCEPROP 2 LAST CDS_LIB pure_quanta
J 0
(-8250 3825);
DISPLAY INVISIBLE (-8250 3825);
FORCEADD Q_RES..1
(-8250 3725);
FORCEPROP 1 LAST LOCATION PR2517
J 0
(-8475 3725);
DISPLAY 0.638298 (-8475 3725);
FORCEPROP 0 LAST $SEC 1
J 0
(-8100 3825);
DISPLAY 0.680851 (-8100 3825);
PAINT MONO (-8100 3825);
DISPLAY INVISIBLE (-8100 3825);
FORCEPROP 0 LAST CDS_SEC 1
J 0
(-8100 3825);
DISPLAY 0.680851 (-8100 3825);
DISPLAY INVISIBLE (-8100 3825);
FORCEPROP 1 LASTPIN (-8350 3725) $PN 1
J 0
(-8338 3737);
DISPLAY 0.787234 (-8338 3737);
PAINT MONO (-8338 3737);
FORCEPROP 1 LASTPIN (-8150 3725) $PN 2
J 0
(-8188 3737);
DISPLAY 0.787234 (-8188 3737);
PAINT MONO (-8188 3737);
FORCEPROP 1 LAST VALUE 10
J 2
(-8275 3775);
DISPLAY 0.638298 (-8275 3775);
FORCEPROP 1 LAST MATERIAL CHIP
J 0
(-8100 3775);
DISPLAY 0.638298 (-8100 3775);
FORCEPROP 1 LAST TOLERANCE 1%
J 0
(-8175 3775);
DISPLAY 0.638298 (-8175 3775);
FORCEPROP 0 LAST ROOM HSC BOM2
J 0
(-8825 3725);
DISPLAY 0.680851 (-8825 3725);
FORCEPROP 1 LAST PART_NUMBER CS01002FB07
J 0
(-8300 3825);
DISPLAY 0.978723 (-8300 3825);
DISPLAY INVISIBLE (-8300 3825);
FORCEPROP 1 LAST PATH I85
J 0
(-8300 3875);
DISPLAY 0.978723 (-8300 3875);
PAINT WHITE (-8300 3875);
DISPLAY INVISIBLE (-8300 3875);
FORCEPROP 2 LAST CDS_LIB pure_quanta
J 0
(-8250 3725);
DISPLAY INVISIBLE (-8250 3725);
FORCEPROP 1 LAST WATTAGE 1/16W
J 2
(-8325 3675);
DISPLAY 0.638298 (-8325 3675);
DISPLAY INVISIBLE (-8325 3675);
FORCEPROP 1 LAST PACK_TYPE 0402LF
J 0
(-8150 3675);
DISPLAY 0.638298 (-8150 3675);
DISPLAY INVISIBLE (-8150 3675);
FORCEADD Q_RES..1
(-8250 3625);
FORCEPROP 1 LAST LOCATION PR2518
J 0
(-8500 3625);
DISPLAY 0.638298 (-8500 3625);
FORCEPROP 0 LAST $SEC 1
J 0
(-8125 3725);
DISPLAY 0.680851 (-8125 3725);
PAINT MONO (-8125 3725);
DISPLAY INVISIBLE (-8125 3725);
FORCEPROP 0 LAST CDS_SEC 1
J 0
(-8125 3725);
DISPLAY 0.680851 (-8125 3725);
DISPLAY INVISIBLE (-8125 3725);
FORCEPROP 1 LASTPIN (-8350 3625) $PN 1
J 0
(-8338 3637);
DISPLAY 0.787234 (-8338 3637);
PAINT MONO (-8338 3637);
FORCEPROP 1 LASTPIN (-8150 3625) $PN 2
J 0
(-8188 3637);
DISPLAY 0.787234 (-8188 3637);
PAINT MONO (-8188 3637);
FORCEPROP 1 LAST VALUE 10
J 2
(-8275 3675);
DISPLAY 0.638298 (-8275 3675);
FORCEPROP 1 LAST MATERIAL CHIP
J 0
(-8125 3675);
DISPLAY 0.638298 (-8125 3675);
FORCEPROP 1 LAST TOLERANCE 1%
J 0
(-8200 3675);
DISPLAY 0.638298 (-8200 3675);
FORCEPROP 0 LAST ROOM HSC BOM2
J 0
(-8850 3625);
DISPLAY 0.680851 (-8850 3625);
FORCEPROP 1 LAST PART_NUMBER CS01002FB07
J 0
(-8300 3725);
DISPLAY 0.978723 (-8300 3725);
DISPLAY INVISIBLE (-8300 3725);
FORCEPROP 1 LAST PATH I86
J 0
(-8300 3775);
DISPLAY 0.978723 (-8300 3775);
PAINT WHITE (-8300 3775);
DISPLAY INVISIBLE (-8300 3775);
FORCEPROP 1 LAST PACK_TYPE 0402LF
J 0
(-8150 3575);
DISPLAY 0.638298 (-8150 3575);
DISPLAY INVISIBLE (-8150 3575);
FORCEPROP 1 LAST WATTAGE 1/16W
J 2
(-8325 3575);
DISPLAY 0.638298 (-8325 3575);
DISPLAY INVISIBLE (-8325 3575);
FORCEPROP 2 LAST CDS_LIB pure_quanta
J 0
(-8250 3625);
DISPLAY INVISIBLE (-8250 3625);
FORCEADD Q_RES..1
(-8250 3525);
FORCEPROP 1 LAST LOCATION PR2519
J 0
(-8500 3525);
DISPLAY 0.638298 (-8500 3525);
FORCEPROP 0 LAST $SEC 1
J 0
(-8125 3625);
DISPLAY 0.680851 (-8125 3625);
PAINT MONO (-8125 3625);
DISPLAY INVISIBLE (-8125 3625);
FORCEPROP 0 LAST CDS_SEC 1
J 0
(-8125 3625);
DISPLAY 0.680851 (-8125 3625);
DISPLAY INVISIBLE (-8125 3625);
FORCEPROP 1 LASTPIN (-8350 3525) $PN 1
J 0
(-8338 3537);
DISPLAY 0.787234 (-8338 3537);
PAINT MONO (-8338 3537);
FORCEPROP 1 LASTPIN (-8150 3525) $PN 2
J 0
(-8188 3537);
DISPLAY 0.787234 (-8188 3537);
PAINT MONO (-8188 3537);
FORCEPROP 1 LAST VALUE 100
J 2
(-8275 3575);
DISPLAY 0.638298 (-8275 3575);
FORCEPROP 1 LAST MATERIAL CHIP
J 0
(-8125 3575);
DISPLAY 0.638298 (-8125 3575);
FORCEPROP 1 LAST TOLERANCE 1%
J 0
(-8200 3575);
DISPLAY 0.638298 (-8200 3575);
FORCEPROP 0 LAST ROOM HSC BOM2
J 0
(-8825 3525);
DISPLAY 0.680851 (-8825 3525);
FORCEPROP 1 LAST PART_NUMBER CS11002FB07
J 0
(-8300 3625);
DISPLAY 0.978723 (-8300 3625);
DISPLAY INVISIBLE (-8300 3625);
FORCEPROP 1 LAST PATH I87
J 0
(-8300 3675);
DISPLAY 0.978723 (-8300 3675);
PAINT WHITE (-8300 3675);
DISPLAY INVISIBLE (-8300 3675);
FORCEPROP 2 LAST CDS_LIB pure_quanta
J 0
(-8250 3525);
DISPLAY INVISIBLE (-8250 3525);
FORCEPROP 1 LAST PACK_TYPE 0402LF
J 0
(-8000 3375);
DISPLAY 0.978723 (-8000 3375);
DISPLAY INVISIBLE (-8000 3375);
FORCEPROP 1 LAST WATTAGE 1/16W
J 2
(-8275 3375);
DISPLAY 0.978723 (-8275 3375);
DISPLAY INVISIBLE (-8275 3375);
FORCEADD Q_RES..1
(-8225 2400);
FORCEPROP 1 LAST LOCATION PR2524
J 0
(-8475 2400);
DISPLAY 0.638298 (-8475 2400);
FORCEPROP 0 LAST $SEC 1
J 0
(-8125 2500);
DISPLAY 0.680851 (-8125 2500);
PAINT MONO (-8125 2500);
DISPLAY INVISIBLE (-8125 2500);
FORCEPROP 0 LAST CDS_SEC 1
J 0
(-8125 2500);
DISPLAY 0.680851 (-8125 2500);
DISPLAY INVISIBLE (-8125 2500);
FORCEPROP 1 LASTPIN (-8325 2400) $PN 1
J 0
(-8313 2412);
DISPLAY 0.787234 (-8313 2412);
PAINT MONO (-8313 2412);
FORCEPROP 1 LASTPIN (-8125 2400) $PN 2
J 0
(-8163 2412);
DISPLAY 0.787234 (-8163 2412);
PAINT MONO (-8163 2412);
FORCEPROP 0 LAST ROOM HSC BOM2
J 0
(-8850 2400);
DISPLAY 0.680851 (-8850 2400);
FORCEPROP 1 LAST VALUE 10
J 2
(-8275 2450);
DISPLAY 0.638298 (-8275 2450);
FORCEPROP 1 LAST MATERIAL CHIP
J 0
(-8125 2450);
DISPLAY 0.638298 (-8125 2450);
FORCEPROP 1 LAST TOLERANCE 1%
J 0
(-8200 2450);
DISPLAY 0.638298 (-8200 2450);
FORCEPROP 1 LAST PART_NUMBER CS01002FB07
J 0
(-8275 2500);
DISPLAY 0.978723 (-8275 2500);
DISPLAY INVISIBLE (-8275 2500);
FORCEPROP 1 LAST PATH I88
J 0
(-8275 2550);
DISPLAY 0.978723 (-8275 2550);
PAINT WHITE (-8275 2550);
DISPLAY INVISIBLE (-8275 2550);
FORCEPROP 1 LAST PACK_TYPE 0402LF
J 0
(-8125 2350);
DISPLAY 0.638298 (-8125 2350);
DISPLAY INVISIBLE (-8125 2350);
FORCEPROP 1 LAST WATTAGE 1/16W
J 2
(-8300 2350);
DISPLAY 0.638298 (-8300 2350);
DISPLAY INVISIBLE (-8300 2350);
FORCEPROP 2 LAST CDS_LIB pure_quanta
J 0
(-8225 2400);
DISPLAY INVISIBLE (-8225 2400);
FORCEADD Q_RES..1
(-8225 2300);
FORCEPROP 1 LAST LOCATION PR2525
J 0
(-8475 2300);
DISPLAY 0.638298 (-8475 2300);
FORCEPROP 0 LAST $SEC 1
J 0
(-8125 2400);
DISPLAY 0.680851 (-8125 2400);
PAINT MONO (-8125 2400);
DISPLAY INVISIBLE (-8125 2400);
FORCEPROP 0 LAST CDS_SEC 1
J 0
(-8125 2400);
DISPLAY 0.680851 (-8125 2400);
DISPLAY INVISIBLE (-8125 2400);
FORCEPROP 1 LASTPIN (-8325 2300) $PN 1
J 0
(-8313 2312);
DISPLAY 0.787234 (-8313 2312);
PAINT MONO (-8313 2312);
FORCEPROP 1 LASTPIN (-8125 2300) $PN 2
J 0
(-8163 2312);
DISPLAY 0.787234 (-8163 2312);
PAINT MONO (-8163 2312);
FORCEPROP 0 LAST ROOM HSC BOM2
J 0
(-8850 2300);
DISPLAY 0.680851 (-8850 2300);
FORCEPROP 1 LAST VALUE 10
J 2
(-8275 2350);
DISPLAY 0.638298 (-8275 2350);
FORCEPROP 1 LAST TOLERANCE 1%
J 0
(-8200 2350);
DISPLAY 0.638298 (-8200 2350);
FORCEPROP 1 LAST MATERIAL CHIP
J 0
(-8125 2350);
DISPLAY 0.638298 (-8125 2350);
FORCEPROP 1 LAST PART_NUMBER CS01002FB07
J 0
(-8275 2400);
DISPLAY 0.978723 (-8275 2400);
DISPLAY INVISIBLE (-8275 2400);
FORCEPROP 1 LAST PATH I89
J 0
(-8275 2450);
DISPLAY 0.978723 (-8275 2450);
PAINT WHITE (-8275 2450);
DISPLAY INVISIBLE (-8275 2450);
FORCEPROP 2 LAST CDS_LIB pure_quanta
J 0
(-8225 2300);
DISPLAY INVISIBLE (-8225 2300);
FORCEPROP 1 LAST WATTAGE 1/16W
J 2
(-8300 2250);
DISPLAY 0.638298 (-8300 2250);
DISPLAY INVISIBLE (-8300 2250);
FORCEPROP 1 LAST PACK_TYPE 0402LF
J 0
(-8125 2250);
DISPLAY 0.638298 (-8125 2250);
DISPLAY INVISIBLE (-8125 2250);
FORCEADD Q_RES..1
(-8225 2200);
FORCEPROP 1 LAST LOCATION PR2526
J 0
(-8475 2200);
DISPLAY 0.638298 (-8475 2200);
FORCEPROP 0 LAST $SEC 1
J 0
(-8125 2300);
DISPLAY 0.680851 (-8125 2300);
PAINT MONO (-8125 2300);
DISPLAY INVISIBLE (-8125 2300);
FORCEPROP 0 LAST CDS_SEC 1
J 0
(-8125 2300);
DISPLAY 0.680851 (-8125 2300);
DISPLAY INVISIBLE (-8125 2300);
FORCEPROP 1 LASTPIN (-8325 2200) $PN 1
J 0
(-8313 2212);
DISPLAY 0.787234 (-8313 2212);
PAINT MONO (-8313 2212);
FORCEPROP 1 LASTPIN (-8125 2200) $PN 2
J 0
(-8163 2212);
DISPLAY 0.787234 (-8163 2212);
PAINT MONO (-8163 2212);
FORCEPROP 0 LAST ROOM HSC BOM2
J 0
(-8850 2200);
DISPLAY 0.680851 (-8850 2200);
FORCEPROP 1 LAST TOLERANCE 1%
J 0
(-8200 2250);
DISPLAY 0.638298 (-8200 2250);
FORCEPROP 1 LAST MATERIAL CHIP
J 0
(-8125 2250);
DISPLAY 0.638298 (-8125 2250);
FORCEPROP 1 LAST VALUE 10
J 2
(-8275 2250);
DISPLAY 0.638298 (-8275 2250);
FORCEPROP 1 LAST PART_NUMBER CS01002FB07
J 0
(-8275 2300);
DISPLAY 0.978723 (-8275 2300);
DISPLAY INVISIBLE (-8275 2300);
FORCEPROP 1 LAST PATH I90
J 0
(-8275 2350);
DISPLAY 0.978723 (-8275 2350);
PAINT WHITE (-8275 2350);
DISPLAY INVISIBLE (-8275 2350);
FORCEPROP 2 LAST CDS_LIB pure_quanta
J 0
(-8225 2200);
DISPLAY INVISIBLE (-8225 2200);
FORCEPROP 1 LAST WATTAGE 1/16W
J 2
(-8300 2150);
DISPLAY 0.638298 (-8300 2150);
DISPLAY INVISIBLE (-8300 2150);
FORCEPROP 1 LAST PACK_TYPE 0402LF
J 0
(-8125 2150);
DISPLAY 0.638298 (-8125 2150);
DISPLAY INVISIBLE (-8125 2150);
FORCEADD Q_RES..1
(-8225 2100);
FORCEPROP 1 LAST LOCATION PR2527
J 0
(-8475 2100);
DISPLAY 0.638298 (-8475 2100);
FORCEPROP 0 LAST $SEC 1
J 0
(-8125 2200);
DISPLAY 0.680851 (-8125 2200);
PAINT MONO (-8125 2200);
DISPLAY INVISIBLE (-8125 2200);
FORCEPROP 0 LAST CDS_SEC 1
J 0
(-8125 2200);
DISPLAY 0.680851 (-8125 2200);
DISPLAY INVISIBLE (-8125 2200);
FORCEPROP 1 LASTPIN (-8325 2100) $PN 1
J 0
(-8313 2112);
DISPLAY 0.787234 (-8313 2112);
PAINT MONO (-8313 2112);
FORCEPROP 1 LASTPIN (-8125 2100) $PN 2
J 0
(-8163 2112);
DISPLAY 0.787234 (-8163 2112);
PAINT MONO (-8163 2112);
FORCEPROP 0 LAST ROOM HSC BOM2
J 0
(-8850 2100);
DISPLAY 0.680851 (-8850 2100);
FORCEPROP 1 LAST TOLERANCE 1%
J 0
(-8200 2150);
DISPLAY 0.638298 (-8200 2150);
FORCEPROP 1 LAST VALUE 10
J 2
(-8275 2150);
DISPLAY 0.638298 (-8275 2150);
FORCEPROP 1 LAST MATERIAL CHIP
J 0
(-8125 2150);
DISPLAY 0.638298 (-8125 2150);
FORCEPROP 1 LAST PART_NUMBER CS01002FB07
J 0
(-8275 2200);
DISPLAY 0.978723 (-8275 2200);
DISPLAY INVISIBLE (-8275 2200);
FORCEPROP 1 LAST PATH I91
J 0
(-8275 2250);
DISPLAY 0.978723 (-8275 2250);
PAINT WHITE (-8275 2250);
DISPLAY INVISIBLE (-8275 2250);
FORCEPROP 2 LAST CDS_LIB pure_quanta
J 0
(-8225 2100);
DISPLAY INVISIBLE (-8225 2100);
FORCEPROP 1 LAST WATTAGE 1/16W
J 2
(-8300 2050);
DISPLAY 0.638298 (-8300 2050);
DISPLAY INVISIBLE (-8300 2050);
FORCEPROP 1 LAST PACK_TYPE 0402LF
J 0
(-8125 2050);
DISPLAY 0.638298 (-8125 2050);
DISPLAY INVISIBLE (-8125 2050);
FORCEADD DNS..2
(-1150 1275);
PAINT RED (-1150 1275);
FORCEPROP 1 LAST COMMENT_BODY TRUE
R 1
J 0
(-1075 1050);
DISPLAY 0.872340 (-1075 1050);
PAINT GREEN (-1075 1050);
DISPLAY INVISIBLE (-1075 1050);
FORCEPROP 2 LAST CDS_LIB mstr_misc
J 0
(-1150 1275);
DISPLAY INVISIBLE (-1150 1275);
FORCEADD DNS..2
(-1150 1575);
PAINT RED (-1150 1575);
FORCEPROP 1 LAST COMMENT_BODY TRUE
R 1
J 0
(-1075 1350);
DISPLAY 0.872340 (-1075 1350);
PAINT GREEN (-1075 1350);
DISPLAY INVISIBLE (-1075 1350);
FORCEPROP 2 LAST CDS_LIB mstr_misc
J 0
(-1150 1575);
DISPLAY INVISIBLE (-1150 1575);
FORCEADD BOM_NOTE..1
(-2775 5600);
FORCEPROP 0 LAST NOTE PR6002 CHANGE TO CS+003DFR03
J 0
(-2950 5500);
DISPLAY 0.680851 (-2950 5500);
PAINT SKYBLUE (-2950 5500);
FORCEPROP 1 LAST COMMENT_BODY TRUE
J 0
(-2750 5700);
DISPLAY 0.978723 (-2750 5700);
DISPLAY INVISIBLE (-2750 5700);
FORCEPROP 2 LAST CDS_LIB pure_quanta_power
J 0
(-2775 5600);
DISPLAY INVISIBLE (-2775 5600);
FORCEADD DNS..2
(-1625 1575);
PAINT RED (-1625 1575);
FORCEPROP 1 LAST COMMENT_BODY TRUE
R 1
J 0
(-1550 1350);
DISPLAY 0.872340 (-1550 1350);
PAINT GREEN (-1550 1350);
DISPLAY INVISIBLE (-1550 1350);
FORCEPROP 2 LAST CDS_LIB mstr_misc
J 0
(-1625 1575);
DISPLAY INVISIBLE (-1625 1575);
FORCEADD QUANTA_TITLE_BLOCK_C..1
(0 0);
FORCEPROP 0 LAST CDS_CON_LAST_MODIFIED Thu Sep 14 16:12:45 2023
J 0
(-1885 15);
DISPLAY INVISIBLE (-1885 15);
FORCEPROP 1 LAST CUSTOM_TXT_CDS <CON_LAST_MODIFIED>
J 0
(-1885 15);
DISPLAY 0.978723 (-1885 15);
FORCEPROP 2 LAST CUSTOM_TXT_CDS <XR_PAGE_TITLE>
J 0
(-7890 5250);
DISPLAY 0.638298 (-7890 5250);
PAINT PINK (-7890 5250);
DISPLAY INVISIBLE (-7890 5250);
FORCEPROP 1 LAST CUSTOM_TXT_CDS <NAME_2>
J 0
(-3175 50);
FORCEPROP 1 LAST CUSTOM_TXT_CDS <NAME_1>
J 0
(-3175 175);
FORCEPROP 1 LAST CUSTOM_TXT_CDS <Q_NUMBER>
J 0
(-1403 103);
DISPLAY 1.212766 (-1403 103);
FORCEPROP 1 LAST CUSTOM_TXT_CDS <Q_PROJ>
J 0
(-2382 102);
DISPLAY 1.212766 (-2382 102);
FORCEPROP 1 LAST CUSTOM_TXT_CDS <Q_REV>
J 0
(-184 103);
DISPLAY 1.212766 (-184 103);
FORCEPROP 1 LAST CUSTOM_TXT_CDS <CON_PAGE_NUM> OF <CON_TOTAL_PAGES>
J 0
(-446 18);
DISPLAY 0.978723 (-446 18);
FORCEPROP 1 LAST Q_TITLE P12V HOTSWAP FOR MODULE(1/2)
J 0
(-9366 26);
DISPLAY 2.446809 (-9366 26);
PAINT GREEN (-9366 26);
FORCEPROP 1 LAST COMMENT_BODY TRUE
J 0
(12 -13);
DISPLAY 0.978723 (12 -13);
PAINT GREEN (12 -13);
DISPLAY INVISIBLE (12 -13);
FORCEPROP 1 LAST Q_DEPT BU9
J 1
(-3763 49);
DISPLAY 1.957447 (-3763 49);
PAINT GREEN (-3763 49);
DISPLAY INVISIBLE (-3763 49);
FORCEPROP 2 LAST CDS_XR_PAGE_TITLE CR-267 : @T6G_MB_LIB.T6G(SCH_1):PAGE267
J 0
(-7890 5250);
DISPLAY 0.638298 (-7890 5250);
PAINT PINK (-7890 5250);
DISPLAY INVISIBLE (-7890 5250);
FORCEPROP 1 LAST CDS_LMAN_SYM_OUTLINE -9475,6775,100,-125
J 0
(0 0);
DISPLAY 0.468085 (0 0);
PAINT GREEN (0 0);
DISPLAY INVISIBLE (0 0);
FORCEPROP 2 LAST CDS_LIB pure_quanta
J 0
(0 0);
DISPLAY INVISIBLE (0 0);
FORCEPROP 2 LAST PAGE_BORDER TRUE
J 0
(-7890 5250);
DISPLAY 0.638298 (-7890 5250);
PAINT PINK (-7890 5250);
DISPLAY INVISIBLE (-7890 5250);
WIRE 16 -1 (-3700 5225)(-3850 5225);
WIRE 16 -1 (-3850 5225)(-3850 4975);
WIRE 16 -1 (-4875 5225)(-3850 5225);
WIRE 16 -1 (-4875 5225)(-4875 5300);
WIRE 16 -1 (-3850 4975)(-3700 4975);
WIRE 16 -1 (-3850 4975)(-3850 4425);
WIRE 16 -1 (-3850 4425)(-3725 4425);
WIRE 16 -1 (-3850 3850)(-3850 4425);
WIRE 16 -1 (-3850 3850)(-3725 3850);
WIRE 16 -1 (-3850 3250)(-3850 3850);
WIRE 16 -1 (-3850 3250)(-3725 3250);
WIRE 16 -1 (-425 975)(-425 1100);
WIRE 16 -1 (-425 975)(-475 975);
WIRE 16 -1 (-475 925)(-475 975);
WIRE 16 -1 (-475 975)(-525 975);
WIRE 16 -1 (-525 1100)(-525 975);
WIRE 16 -1 (-275 3175)(-275 3275);
WIRE 16 -1 (-275 3175)(-375 3175);
WIRE 16 -1 (-375 3275)(-375 3175);
WIRE 16 -1 (-425 3175)(-375 3175);
WIRE 16 -1 (-475 3175)(-425 3175);
WIRE 16 -1 (-425 3175)(-425 1800);
WIRE 16 -1 (-425 1800)(-475 1800);
WIRE 16 -1 (-475 3275)(-475 3175);
WIRE 16 -1 (-475 1800)(-475 1650);
WIRE 16 -1 (-850 1800)(-475 1800);
WIRE 16 -1 (-850 2125)(-850 1800);
WIRE 16 -1 (-1175 1800)(-850 1800);
WIRE 16 -1 (-1175 1700)(-1175 1800);
WIRE 16 -1 (-1650 1800)(-1175 1800);
WIRE 16 -1 (-1650 1800)(-1725 1800);
WIRE 16 -1 (-1650 1800)(-1650 1675);
WIRE 16 -1 (-1725 2125)(-1725 1800);
WIRE 16 -1 (-1825 1800)(-1725 1800);
WIRE 16 -1 (-1825 2125)(-1825 1800);
WIRE 16 -1 (-1825 1800)(-1925 1800);
WIRE 16 -1 (-1925 2125)(-1925 1800);
WIRE 16 -1 (-2600 1800)(-1925 1800);
WIRE 16 -1 (-2600 2100)(-2600 1800);
WIRE 16 -1 (-2600 1800)(-2700 1800);
WIRE 16 -1 (-2700 2100)(-2700 1800);
WIRE 16 -1 (-2700 1800)(-2800 1800);
WIRE 16 -1 (-2800 2100)(-2800 1800);
WIRE 16 -1 (-3475 1800)(-2800 1800);
WIRE 16 -1 (-3475 2075)(-3475 1800);
WIRE 16 -1 (-3475 1800)(-3575 1800);
WIRE 16 -1 (-3575 2075)(-3575 1800);
WIRE 16 -1 (-3575 1800)(-3675 1800);
WIRE 16 -1 (-3675 2075)(-3675 1800);
WIRE 16 -1 (-4350 1800)(-3675 1800);
WIRE 16 -1 (-4350 2075)(-4350 1800);
WIRE 16 -1 (-4350 1800)(-4450 1800);
WIRE 16 -1 (-4450 2075)(-4450 1800);
WIRE 16 -1 (-4450 1800)(-4550 1800);
WIRE 16 -1 (-4550 2075)(-4550 1800);
WIRE 16 -1 (-5225 1800)(-4550 1800);
WIRE 16 -1 (-5225 2050)(-5225 1800);
WIRE 16 -1 (-5225 1800)(-5325 1800);
WIRE 16 -1 (-5325 2050)(-5325 1800);
WIRE 16 -1 (-5325 1800)(-5425 1800);
WIRE 16 -1 (-5425 2050)(-5425 1800);
WIRE 16 -1 (-5425 1800)(-6100 1800);
WIRE 16 -1 (-6100 2025)(-6100 1800);
WIRE 16 -1 (-6100 1800)(-6200 1800);
WIRE 16 -1 (-6200 2025)(-6200 1800);
WIRE 16 -1 (-6300 1800)(-6200 1800);
WIRE 16 -1 (-6300 2025)(-6300 1800);
WIRE 16 -1 (-3325 3250)(-3125 3250);
WIRE 16 -1 (-3125 3250)(-3125 3850);
WIRE 16 -1 (-3125 3850)(-3125 4425);
WIRE 16 -1 (-3325 3850)(-3125 3850);
WIRE 16 -1 (-3125 4975)(-3125 4425);
WIRE 16 -1 (-3325 4425)(-3125 4425);
WIRE 16 -1 (-3125 4975)(-1750 4975);
WIRE 16 -1 (-3125 4975)(-3300 4975);
WIRE 16 -1 (-1750 2700)(-1750 4975);
WIRE 16 -1 (-1750 4975)(-1750 5000);
WIRE 16 -1 (-1750 2700)(-1825 2700);
WIRE 16 -1 (-1825 2625)(-1825 2700);
WIRE 16 -1 (-1825 2700)(-1925 2700);
WIRE 16 -1 (-1925 2700)(-1925 2701);
WIRE 16 -1 (-2700 2701)(-1925 2701);
WIRE 16 -1 (-2700 2600)(-2700 2701);
WIRE 16 -1 (-2700 2701)(-3575 2701);
WIRE 16 -1 (-3575 2700)(-3575 2701);
WIRE 16 -1 (-3575 2575)(-3575 2700);
WIRE 16 -1 (-4450 2700)(-3575 2700);
WIRE 16 -1 (-4450 2575)(-4450 2700);
WIRE 16 -1 (-5325 2700)(-4450 2700);
WIRE 16 -1 (-5325 2550)(-5325 2700);
WIRE 16 -1 (-6200 2700)(-5325 2700);
WIRE 16 -1 (-6200 2525)(-6200 2700);
WIRE 16 -1 (-375 3775)(-375 5225);
WIRE 16 -1 (-375 5225)(-1350 5225);
WIRE 16 -1 (-3300 5225)(-1350 5225);
WIRE 16 -1 (-1350 5225)(-1350 5250);
WIRE 16 -1 (-6550 1675)(-6550 2225);
FORCEPROP 2 LAST SIG_NAME P12V_HSC_GATE_G1
R 1
J 0
(-6560 1650);
DISPLAY 0.723404 (-6560 1650);
FORCEPROP 2 LASTPROP $XRERR UNIQUE?
J 0
(-6800 1650);
DISPLAY 0.638298 (-6800 1650);
PAINT MONO (-6800 1650);
DISPLAY INVISIBLE (-6800 1650);
WIRE 16 -1 (-6550 2225)(-6400 2225);
WIRE 16 -1 (-5675 1675)(-5675 2250);
FORCEPROP 2 LAST SIG_NAME P12V_HSC_GATE_G2
R 1
J 0
(-5685 1650);
DISPLAY 0.723404 (-5685 1650);
FORCEPROP 2 LASTPROP $XRERR UNIQUE?
J 0
(-5925 1650);
DISPLAY 0.638298 (-5925 1650);
PAINT MONO (-5925 1650);
DISPLAY INVISIBLE (-5925 1650);
WIRE 16 -1 (-5675 2250)(-5525 2250);
WIRE 16 -1 (-4825 1675)(-4825 2275);
FORCEPROP 2 LAST SIG_NAME P12V_HSC_GATE_G3
R 1
J 0
(-4835 1650);
DISPLAY 0.723404 (-4835 1650);
FORCEPROP 2 LASTPROP $XRERR UNIQUE?
J 0
(-5075 1650);
DISPLAY 0.638298 (-5075 1650);
PAINT MONO (-5075 1650);
DISPLAY INVISIBLE (-5075 1650);
WIRE 16 -1 (-4825 2275)(-4650 2275);
WIRE 16 -1 (-3975 1675)(-3975 2275);
FORCEPROP 2 LAST SIG_NAME P12V_HSC_GATE_G4
R 1
J 0
(-3985 1660);
DISPLAY 0.723404 (-3985 1660);
FORCEPROP 2 LASTPROP $XRERR UNIQUE?
J 0
(-4225 1660);
DISPLAY 0.638298 (-4225 1660);
PAINT MONO (-4225 1660);
DISPLAY INVISIBLE (-4225 1660);
WIRE 16 -1 (-3975 2275)(-3775 2275);
WIRE 16 -1 (-2900 2300)(-3125 2300);
WIRE 16 -1 (-3125 2300)(-3125 1675);
FORCEPROP 2 LAST SIG_NAME P12V_HSC_GATE_G5
R 1
J 0
(-3135 1660);
DISPLAY 0.723404 (-3135 1660);
FORCEPROP 2 LASTPROP $XRERR UNIQUE?
J 0
(-3375 1660);
DISPLAY 0.638298 (-3375 1660);
PAINT MONO (-3375 1660);
DISPLAY INVISIBLE (-3375 1660);
WIRE 16 -1 (-5850 1175)(-5850 1350);
WIRE 16 -1 (-5850 1175)(-6950 1175);
FORCEPROP 2 LAST SIG_NAME P12V_HSC_GATE2
J 0
(-6917 1192);
DISPLAY 0.723404 (-6917 1192);
WIRE 16 -1 (-5675 1350)(-5850 1350);
WIRE 16 -1 (-6550 1350)(-5850 1350);
WIRE 16 -1 (-6550 1350)(-6550 1475);
WIRE 16 -1 (-5675 1350)(-4825 1350);
WIRE 16 -1 (-5675 1475)(-5675 1350);
WIRE 16 -1 (-3975 1350)(-4825 1350);
WIRE 16 -1 (-4825 1475)(-4825 1350);
WIRE 16 -1 (-3975 1350)(-3125 1350);
WIRE 16 -1 (-3975 1475)(-3975 1350);
WIRE 16 -1 (-3125 1350)(-2250 1350);
WIRE 16 -1 (-3125 1475)(-3125 1350);
WIRE 16 -1 (-2250 1350)(-1650 1350);
WIRE 16 -1 (-2250 1475)(-2250 1350);
WIRE 16 -1 (-1650 1350)(-1650 1475);
WIRE 16 -1 (-1650 1350)(-1650 1150);
WIRE 16 -1 (-1650 1150)(-1175 1150);
WIRE 16 -1 (-1175 1150)(-1175 1175);
WIRE 16 -1 (-2250 1675)(-2250 2325);
FORCEPROP 2 LAST SIG_NAME P12V_HSC_GATE_G6
R 1
J 0
(-2260 1660);
DISPLAY 0.723404 (-2260 1660);
FORCEPROP 2 LASTPROP $XRERR UNIQUE?
J 0
(-2500 1660);
DISPLAY 0.638298 (-2500 1660);
PAINT MONO (-2500 1660);
DISPLAY INVISIBLE (-2500 1660);
WIRE 16 -1 (-2250 2325)(-2025 2325);
WIRE 16 -1 (-575 3475)(-875 3475);
FORCEPROP 2 LAST SIG_NAME MB0_CM_GATE_G0
R 1
J 0
(-885 3110);
DISPLAY 0.723404 (-885 3110);
FORCEPROP 2 LASTPROP $XRERR UNIQUE?
J 0
(-1125 3110);
DISPLAY 0.638298 (-1125 3110);
PAINT MONO (-1125 3110);
DISPLAY INVISIBLE (-1125 3110);
WIRE 16 -1 (-875 3475)(-875 3125);
WIRE 16 -1 (-4550 4925)(-3700 4925);
FORCEPROP 2 LAST SIG_NAME P12V_HSC_SENSE2_R1_P
J 0
(-4560 4935);
DISPLAY 0.723404 (-4560 4935);
WIRE 16 -1 (-3725 3800)(-4550 3800);
FORCEPROP 2 LAST SIG_NAME P12V_HSC_SENSE2_R3_P
J 0
(-4560 3810);
DISPLAY 0.723404 (-4560 3810);
WIRE 16 -1 (-3325 4375)(-2350 4375);
FORCEPROP 2 LAST SIG_NAME P12V_HSC_SENSE2_R2_N
J 0
(-3010 4385);
DISPLAY 0.723404 (-3010 4385);
WIRE 16 -1 (-3300 5275)(-2325 5275);
FORCEPROP 2 LAST SIG_NAME P12V_HSC_SENSE1_N
J 0
(-3010 5285);
DISPLAY 0.723404 (-3010 5285);
WIRE 16 -1 (-2325 4925)(-3300 4925);
FORCEPROP 2 LAST SIG_NAME P12V_HSC_SENSE2_R1_N
J 0
(-3010 4935);
DISPLAY 0.723404 (-3010 4935);
WIRE 16 -1 (-3325 3800)(-2350 3800);
FORCEPROP 2 LAST SIG_NAME P12V_HSC_SENSE2_R3_N
J 0
(-3010 3810);
DISPLAY 0.723404 (-3010 3810);
WIRE 16 -1 (-3325 3200)(-2350 3200);
FORCEPROP 2 LAST SIG_NAME P12V_HSC_SENSE2_R4_N
J 0
(-3010 3210);
DISPLAY 0.723404 (-3010 3210);
WIRE 16 -1 (-3700 5275)(-4525 5275);
FORCEPROP 2 LAST SIG_NAME P12V_HSC_SENSE1_P
J 0
(-4535 5285);
DISPLAY 0.723404 (-4535 5285);
WIRE 16 -1 (-7300 3050)(-8150 3050);
FORCEPROP 2 LAST SIG_NAME P12V_HSC_SENSE2_R2_P
J 0
(-8010 3060);
DISPLAY 0.723404 (-8010 3060);
WIRE 16 -1 (-7300 2950)(-8150 2950);
FORCEPROP 2 LAST SIG_NAME P12V_HSC_SENSE2_R3_P
J 0
(-8010 2960);
DISPLAY 0.723404 (-8010 2960);
WIRE 16 -1 (-7300 2850)(-8150 2850);
FORCEPROP 2 LAST SIG_NAME P12V_HSC_SENSE2_R4_P
J 0
(-8010 2860);
DISPLAY 0.723404 (-8010 2860);
WIRE 16 -1 (-8550 2500)(-7300 2500);
FORCEPROP 2 LAST SIG_NAME P12V_HSC_SENSE2_N
J 0
(-7985 2510);
DISPLAY 0.723404 (-7985 2510);
WIRE 16 -1 (-8550 2500)(-8550 2400);
WIRE 16 -1 (-8550 2400)(-8325 2400);
WIRE 16 -1 (-8550 2400)(-8550 2300);
WIRE 16 -1 (-8325 2300)(-8550 2300);
WIRE 16 -1 (-8550 2200)(-8550 2300);
WIRE 16 -1 (-8550 2200)(-8325 2200);
WIRE 16 -1 (-8550 2200)(-8550 2100);
WIRE 16 -1 (-8550 2100)(-8325 2100);
WIRE 16 -1 (-8550 3250)(-7300 3250);
FORCEPROP 2 LAST SIG_NAME P12V_HSC_SENSE2_P
J 0
(-8035 3260);
DISPLAY 0.723404 (-8035 3260);
WIRE 16 -1 (-8550 3250)(-8550 3150);
WIRE 16 -1 (-8550 3150)(-8350 3150);
WIRE 16 -1 (-8550 3150)(-8550 3050);
WIRE 16 -1 (-8550 3050)(-8350 3050);
WIRE 16 -1 (-8550 2950)(-8550 3050);
WIRE 16 -1 (-8550 2950)(-8350 2950);
WIRE 16 -1 (-8550 2950)(-8550 2850);
WIRE 16 -1 (-8550 2850)(-8350 2850);
WIRE 16 -1 (-7300 2400)(-8125 2400);
FORCEPROP 2 LAST SIG_NAME P12V_HSC_SENSE2_R1_N
J 0
(-7985 2410);
DISPLAY 0.723404 (-7985 2410);
WIRE 16 -1 (-7300 2300)(-8125 2300);
FORCEPROP 2 LAST SIG_NAME P12V_HSC_SENSE2_R2_N
J 0
(-7985 2310);
DISPLAY 0.723404 (-7985 2310);
WIRE 16 -1 (-7300 2200)(-8125 2200);
FORCEPROP 2 LAST SIG_NAME P12V_HSC_SENSE2_R3_N
J 0
(-7985 2210);
DISPLAY 0.723404 (-7985 2210);
WIRE 16 -1 (-7300 2100)(-8125 2100);
FORCEPROP 2 LAST SIG_NAME P12V_HSC_SENSE2_R4_N
J 0
(-7985 2110);
DISPLAY 0.723404 (-7985 2110);
WIRE 16 -1 (-8550 4025)(-7325 4025);
FORCEPROP 2 LAST SIG_NAME P12V_HSC_ADC_N
J 0
(-8010 4035);
DISPLAY 0.723404 (-8010 4035);
WIRE 16 -1 (-8550 4025)(-8550 3925);
WIRE 16 -1 (-8550 3925)(-8350 3925);
WIRE 16 -1 (-8550 3925)(-8550 3825);
WIRE 16 -1 (-8350 3825)(-8550 3825);
WIRE 16 -1 (-8550 3725)(-8550 3825);
WIRE 16 -1 (-8550 3725)(-8350 3725);
WIRE 16 -1 (-8550 3725)(-8550 3625);
WIRE 16 -1 (-8550 3625)(-8350 3625);
WIRE 16 -1 (-8550 3625)(-8550 3525);
WIRE 16 -1 (-8550 3525)(-8350 3525);
WIRE 16 -1 (-8550 4775)(-7325 4775);
FORCEPROP 2 LAST SIG_NAME P12V_HSC_ADC_P
J 0
(-8035 4785);
DISPLAY 0.723404 (-8035 4785);
WIRE 16 -1 (-8550 4775)(-8550 4675);
WIRE 16 -1 (-8550 4675)(-8375 4675);
WIRE 16 -1 (-8550 4675)(-8550 4575);
WIRE 16 -1 (-8550 4575)(-8375 4575);
WIRE 16 -1 (-8550 4475)(-8550 4575);
WIRE 16 -1 (-8550 4475)(-8375 4475);
WIRE 16 -1 (-8550 4475)(-8550 4375);
WIRE 16 -1 (-8550 4375)(-8375 4375);
WIRE 16 -1 (-8550 4375)(-8550 4275);
WIRE 16 -1 (-8550 4275)(-8375 4275);
WIRE 16 -1 (-7325 4275)(-8175 4275);
FORCEPROP 2 LAST SIG_NAME P12V_HSC_SENSE1_P
J 0
(-8035 4285);
DISPLAY 0.723404 (-8035 4285);
WIRE 16 -1 (-7325 4375)(-8175 4375);
FORCEPROP 2 LAST SIG_NAME P12V_HSC_SENSE2_R4_P
J 0
(-8035 4385);
DISPLAY 0.723404 (-8035 4385);
WIRE 16 -1 (-7325 4475)(-8175 4475);
FORCEPROP 2 LAST SIG_NAME P12V_HSC_SENSE2_R3_P
J 0
(-8035 4485);
DISPLAY 0.723404 (-8035 4485);
WIRE 16 -1 (-7325 4575)(-8175 4575);
FORCEPROP 2 LAST SIG_NAME P12V_HSC_SENSE2_R2_P
J 0
(-8035 4585);
DISPLAY 0.723404 (-8035 4585);
WIRE 16 -1 (-7325 4675)(-8175 4675);
FORCEPROP 2 LAST SIG_NAME P12V_HSC_SENSE2_R1_P
J 0
(-8035 4685);
DISPLAY 0.723404 (-8035 4685);
WIRE 16 -1 (-7325 3825)(-8150 3825);
FORCEPROP 2 LAST SIG_NAME P12V_HSC_SENSE2_R2_N
J 0
(-8010 3835);
DISPLAY 0.723404 (-8010 3835);
WIRE 16 -1 (-7325 3725)(-8150 3725);
FORCEPROP 2 LAST SIG_NAME P12V_HSC_SENSE2_R3_N
J 0
(-8010 3735);
DISPLAY 0.723404 (-8010 3735);
WIRE 16 -1 (-7325 3625)(-8150 3625);
FORCEPROP 2 LAST SIG_NAME P12V_HSC_SENSE2_R4_N
J 0
(-8010 3635);
DISPLAY 0.723404 (-8010 3635);
WIRE 16 -1 (-7325 3525)(-8150 3525);
FORCEPROP 2 LAST SIG_NAME P12V_HSC_SENSE1_N
J 0
(-8010 3535);
DISPLAY 0.723404 (-8010 3535);
WIRE 16 -1 (-7300 3150)(-8150 3150);
FORCEPROP 2 LAST SIG_NAME P12V_HSC_SENSE2_R1_P
J 0
(-8010 3160);
DISPLAY 0.723404 (-8010 3160);
WIRE 16 -1 (-7325 3925)(-8150 3925);
FORCEPROP 2 LAST SIG_NAME P12V_HSC_SENSE2_R1_N
J 0
(-8010 3935);
DISPLAY 0.723404 (-8010 3935);
WIRE 16 -1 (-4550 4375)(-3725 4375);
FORCEPROP 2 LAST SIG_NAME P12V_HSC_SENSE2_R2_P
J 0
(-4560 4385);
DISPLAY 0.723404 (-4560 4385);
WIRE 16 -1 (-3725 3200)(-4550 3200);
FORCEPROP 2 LAST SIG_NAME P12V_HSC_SENSE2_R4_P
J 0
(-4560 3210);
DISPLAY 0.723404 (-4560 3210);
WIRE 16 -1 (-1175 1500)(-1175 1375);
FORCEPROP 2 LAST SIG_NAME P12V_HSC_GATE_RC
J 0
(-1160 1435);
DISPLAY 0.723404 (-1160 1435);
FORCEPROP 2 LASTPROP $XRERR UNIQUE?
J 0
(-1400 1435);
DISPLAY 0.638298 (-1400 1435);
PAINT MONO (-1400 1435);
DISPLAY INVISIBLE (-1400 1435);
WIRE 16 -1 (-875 2800)(-875 2925);
WIRE 16 -1 (-875 2800)(-1350 2800);
FORCEPROP 2 LAST SIG_NAME P12V_HSC_GATE1
J 0
(-1360 2810);
DISPLAY 0.723404 (-1360 2810);
DOT 1 (-3850 4425);
DOT 1 (-8550 3925);
DOT 1 (-8550 3825);
DOT 1 (-1350 5225);
DOT 1 (-375 3175);
DOT 1 (-425 3175);
DOT 1 (-850 1800);
DOT 1 (-475 975);
DOT 1 (-1175 1800);
DOT 1 (-1750 4975);
DOT 1 (-3125 4975);
DOT 1 (-3125 3850);
DOT 1 (-1650 1350);
DOT 1 (-2250 1350);
DOT 1 (-3475 1800);
DOT 1 (-3850 4975);
DOT 1 (-3850 3850);
DOT 1 (-3975 1350);
DOT 1 (-4825 1350);
DOT 1 (-5675 1350);
DOT 1 (-5850 1350);
DOT 1 (-6100 1800);
DOT 1 (-6200 1800);
DOT 1 (-8550 4475);
DOT 1 (-8550 3150);
DOT 1 (-8550 2950);
DOT 1 (-1725 1800);
DOT 1 (-1825 1800);
DOT 1 (-2700 2701);
DOT 1 (-2700 1800);
DOT 1 (-2800 1800);
DOT 1 (-3575 1800);
DOT 1 (-3675 1800);
DOT 1 (-3575 2700);
DOT 1 (-4450 2700);
DOT 1 (-4350 1800);
DOT 1 (-4450 1800);
DOT 1 (-4550 1800);
DOT 1 (-5325 2700);
DOT 1 (-5225 1800);
DOT 1 (-5325 1800);
DOT 1 (-5425 1800);
DOT 1 (-8550 4675);
DOT 1 (-8550 4575);
DOT 1 (-8550 4375);
DOT 1 (-8550 3725);
DOT 1 (-8550 3625);
DOT 1 (-8550 3050);
DOT 1 (-8550 2400);
DOT 1 (-8550 2300);
DOT 1 (-8550 2200);
DOT 1 (-3850 5225);
DOT 1 (-3125 4425);
DOT 1 (-1650 1800);
DOT 1 (-475 1800);
DOT 1 (-1925 1800);
DOT 1 (-3125 1350);
DOT 1 (-2600 1800);
DOT 1 (-1825 2700);
FORCENOTE
HOT SWAT CIRCUIT
(-8871 5613) 0;
DISPLAY LEFT (-8871 5613);
DISPLAY 2.000000 (-8871 5613);
FORCENOTE
OCP=240A
(-8875 5509) 0;
DISPLAY LEFT (-8875 5509);
DISPLAY 1.595745 (-8875 5509);
FORCENOTE
OV =14.333V
(-8850 5350) 0;
DISPLAY LEFT (-8850 5350);
DISPLAY 1.021277 (-8850 5350);
FORCENOTE
UV =10.091V
(-8850 5300) 0;
DISPLAY LEFT (-8850 5300);
DISPLAY 1.021277 (-8850 5300);
FORCENOTE
AT 4.5V, ID=300A
(-3921 2729) 0;
DISPLAY LEFT (-3921 2729);
DISPLAY 1.021277 (-3921 2729);
FORCENOTE
RDS(ON)=0.76M OHM 
(-2950 2725) 0;
DISPLAY LEFT (-2950 2725);
DISPLAY 1.021277 (-2950 2725);
FORCENOTE
LATCH OFF MODE
(-8850 5175) 0;
DISPLAY LEFT (-8850 5175);
DISPLAY 1.021277 (-8850 5175);
FORCENOTE
OCW=220A
(-8875 5434) 0;
DISPLAY LEFT (-8875 5434);
DISPLAY 1.595745 (-8875 5434);
FORCENOTE
FPH=220A
(-8150 5434) 0;
DISPLAY LEFT (-8150 5434);
DISPLAY 1.595745 (-8150 5434);
QUIT
